FILE_TYPE = MACRO_DRAWING;
SET COLOR_WIRE YELLOW;
SET COLOR_PROP MONO;
SET COLOR_DOT WHITE;
SET COLOR_ARC YELLOW;
SET COLOR_BODY GREEN;
SET COLOR_NOTE MONO;
SET PROP_DISPLAY VALUE;
SET PAGE_NUMBER P189;
FORCEADD OFFPAGE..1
(-2850 2975);
FORCEPROP 2 LAST $XR0 120 
J 0
(-3102 2975);
DISPLAY 0.638298 (-3102 2975);
PAINT MONO (-3102 2975);
FORCEPROP 2 LAST CDS_LIB mstr_standard
J 0
(-2850 2975);
PAINT ORANGE (-2850 2975);
DISPLAY INVISIBLE (-2850 2975);
FORCEPROP 2 LAST PATH I1
J 0
(-3125 3025);
DISPLAY 1.021277 (-3125 3025);
PAINT ORANGE (-3125 3025);
DISPLAY INVISIBLE (-3125 3025);
FORCEPROP 1 LAST OFFPAGE TRUE
J 0
(-2525 2850);
DISPLAY 0.872340 (-2525 2850);
PAINT GREEN (-2525 2850);
DISPLAY INVISIBLE (-2525 2850);
FORCEPROP 1 LAST COMMENT_BODY TRUE
J 0
(-2725 2875);
DISPLAY 0.872340 (-2725 2875);
PAINT GREEN (-2725 2875);
DISPLAY INVISIBLE (-2725 2875);
FORCEADD OFFPAGE..1
(-2850 4775);
FORCEPROP 2 LAST $XR2 254 
J 0
(-3342 4775);
DISPLAY 0.638298 (-3342 4775);
PAINT MONO (-3342 4775);
FORCEPROP 2 LAST $XR1 245 
J 0
(-3222 4775);
DISPLAY 0.638298 (-3222 4775);
PAINT MONO (-3222 4775);
FORCEPROP 2 LAST $XR0 144 
J 0
(-3102 4775);
DISPLAY 0.638298 (-3102 4775);
PAINT MONO (-3102 4775);
FORCEPROP 2 LAST CDS_LIB mstr_standard
J 0
(-2850 4775);
PAINT ORANGE (-2850 4775);
DISPLAY INVISIBLE (-2850 4775);
FORCEPROP 2 LAST PATH I10
J 0
(-3125 4825);
DISPLAY 1.021277 (-3125 4825);
PAINT ORANGE (-3125 4825);
DISPLAY INVISIBLE (-3125 4825);
FORCEPROP 1 LAST OFFPAGE TRUE
J 0
(-2525 4650);
DISPLAY 0.872340 (-2525 4650);
PAINT GREEN (-2525 4650);
DISPLAY INVISIBLE (-2525 4650);
FORCEPROP 1 LAST COMMENT_BODY TRUE
J 0
(-2725 4675);
DISPLAY 0.872340 (-2725 4675);
PAINT GREEN (-2725 4675);
DISPLAY INVISIBLE (-2725 4675);
FORCEADD OFFPAGE..1
(-2850 4600);
FORCEPROP 2 LAST $XR0 120 
J 0
(-3102 4600);
DISPLAY 0.638298 (-3102 4600);
PAINT MONO (-3102 4600);
FORCEPROP 2 LAST CDS_LIB mstr_standard
J 0
(-2850 4600);
PAINT ORANGE (-2850 4600);
DISPLAY INVISIBLE (-2850 4600);
FORCEPROP 2 LAST PATH I11
J 0
(-3125 4650);
DISPLAY 1.021277 (-3125 4650);
PAINT ORANGE (-3125 4650);
DISPLAY INVISIBLE (-3125 4650);
FORCEPROP 1 LAST OFFPAGE TRUE
J 0
(-2525 4475);
DISPLAY 0.872340 (-2525 4475);
PAINT GREEN (-2525 4475);
DISPLAY INVISIBLE (-2525 4475);
FORCEPROP 1 LAST COMMENT_BODY TRUE
J 0
(-2725 4500);
DISPLAY 0.872340 (-2725 4500);
PAINT GREEN (-2725 4500);
DISPLAY INVISIBLE (-2725 4500);
FORCEADD OFFPAGE..1
(-2850 4400);
FORCEPROP 2 LAST $XR0 120 
J 0
(-3102 4400);
DISPLAY 0.638298 (-3102 4400);
PAINT MONO (-3102 4400);
FORCEPROP 2 LAST CDS_LIB mstr_standard
J 0
(-2850 4400);
PAINT ORANGE (-2850 4400);
DISPLAY INVISIBLE (-2850 4400);
FORCEPROP 2 LAST PATH I12
J 0
(-3100 4450);
DISPLAY 1.021277 (-3100 4450);
PAINT ORANGE (-3100 4450);
DISPLAY INVISIBLE (-3100 4450);
FORCEPROP 1 LAST OFFPAGE TRUE
J 0
(-2525 4275);
DISPLAY 0.872340 (-2525 4275);
PAINT GREEN (-2525 4275);
DISPLAY INVISIBLE (-2525 4275);
FORCEPROP 1 LAST COMMENT_BODY TRUE
J 0
(-2725 4300);
DISPLAY 0.872340 (-2725 4300);
PAINT GREEN (-2725 4300);
DISPLAY INVISIBLE (-2725 4300);
FORCEADD RES..1
(-2100 4225);
FORCEPROP 1 LAST PART_NUMBER G21497-005
J 0
(-1950 4225);
DISPLAY 0.617021 (-1950 4225);
PAINT BLUE (-1950 4225);
FORCEPROP 1 LASTPIN (-2000 4225) $PN 2
J 0
(-2038 4237);
DISPLAY 0.617021 (-2038 4237);
PAINT ORANGE (-2038 4237);
FORCEPROP 1 LAST LOCATION R7G18
J 0
(-2150 4275);
DISPLAY 0.617021 (-2150 4275);
PAINT AQUA (-2150 4275);
FORCEPROP 1 LASTPIN (-2200 4225) $PN 1
J 0
(-2188 4237);
DISPLAY 0.617021 (-2188 4237);
PAINT ORANGE (-2188 4237);
FORCEPROP 1 LAST TOLERANCE 5%
J 0
(-2250 4225);
DISPLAY 0.617021 (-2250 4225);
PAINT SKYBLUE (-2250 4225);
FORCEPROP 1 LAST VALUE 0.0
J 2
(-2275 4225);
DISPLAY 0.617021 (-2275 4225);
PAINT SKYBLUE (-2275 4225);
FORCEPROP 1 LAST MATERIAL EMPTY
J 0
(-2150 4175);
DISPLAY 0.617021 (-2150 4175);
PAINT RED (-2150 4175);
FORCEPROP 1 LAST WATTAGE 1/16W
J 2
(-2175 4175);
DISPLAY 0.617021 (-2175 4175);
PAINT SKYBLUE (-2175 4175);
FORCEPROP 1 LAST PACK_TYPE 0402
J 0
(-2000 4175);
DISPLAY 0.617021 (-2000 4175);
PAINT SKYBLUE (-2000 4175);
FORCEPROP 2 LAST SEC_TYPE 0402
J 0
(-2150 4425);
DISPLAY 1.021277 (-2150 4425);
PAINT ORANGE (-2150 4425);
DISPLAY INVISIBLE (-2150 4425);
FORCEPROP 2 LAST SEC 1
J 0
(-2150 4425);
PAINT MONO (-2150 4425);
DISPLAY INVISIBLE (-2150 4425);
FORCEPROP 2 LAST CDS_LIB mstr_discrete
J 0
(-2100 4225);
PAINT MONO (-2100 4225);
DISPLAY INVISIBLE (-2100 4225);
FORCEPROP 2 LAST BOM_COST DEBUG
J 0
(-2150 4375);
DISPLAY 1.021277 (-2150 4375);
PAINT ORANGE (-2150 4375);
DISPLAY INVISIBLE (-2150 4375);
FORCEPROP 1 LAST PATH I13
J 0
(-2150 4375);
DISPLAY 0.978723 (-2150 4375);
PAINT WHITE (-2150 4375);
DISPLAY INVISIBLE (-2150 4375);
FORCEPROP 2 LAST ROOM BMC_DEBUG_HEADER
J 0
(-2150 4325);
DISPLAY 1.021277 (-2150 4325);
PAINT ORANGE (-2150 4325);
DISPLAY INVISIBLE (-2150 4325);
FORCEPROP 2 LAST CDS_LOCATION R7G18
J 0
(-2150 4275);
DISPLAY 0.617021 (-2150 4275);
PAINT AQUA (-2150 4275);
DISPLAY INVISIBLE (-2150 4275);
FORCEADD OFFPAGE..2
(-1375 3675);
FORCEPROP 2 LAST $XR0 189 
J 0
(-1096 3675);
DISPLAY 0.638298 (-1096 3675);
PAINT MONO (-1096 3675);
FORCEPROP 2 LAST CDS_LIB mstr_standard
J 0
(-1375 3675);
PAINT ORANGE (-1375 3675);
DISPLAY INVISIBLE (-1375 3675);
FORCEPROP 2 LAST PATH I14
J 0
(-1175 3725);
DISPLAY 1.021277 (-1175 3725);
PAINT ORANGE (-1175 3725);
DISPLAY INVISIBLE (-1175 3725);
FORCEPROP 1 LAST OFFPAGE TRUE
J 0
(-1050 3550);
DISPLAY 0.872340 (-1050 3550);
PAINT GREEN (-1050 3550);
DISPLAY INVISIBLE (-1050 3550);
FORCEPROP 1 LAST COMMENT_BODY TRUE
J 0
(-1420 3580);
DISPLAY 0.872340 (-1420 3580);
PAINT GREEN (-1420 3580);
DISPLAY INVISIBLE (-1420 3580);
FORCEADD OFFPAGE..2
(-1375 2975);
FORCEPROP 2 LAST $XR0 189 
J 0
(-1096 2975);
DISPLAY 0.638298 (-1096 2975);
PAINT MONO (-1096 2975);
FORCEPROP 2 LAST CDS_LIB mstr_standard
J 0
(-1375 2975);
PAINT ORANGE (-1375 2975);
DISPLAY INVISIBLE (-1375 2975);
FORCEPROP 2 LAST PATH I15
J 0
(-1175 3025);
DISPLAY 1.021277 (-1175 3025);
PAINT ORANGE (-1175 3025);
DISPLAY INVISIBLE (-1175 3025);
FORCEPROP 1 LAST OFFPAGE TRUE
J 0
(-1050 2850);
DISPLAY 0.872340 (-1050 2850);
PAINT GREEN (-1050 2850);
DISPLAY INVISIBLE (-1050 2850);
FORCEPROP 1 LAST COMMENT_BODY TRUE
J 0
(-1420 2880);
DISPLAY 0.872340 (-1420 2880);
PAINT GREEN (-1420 2880);
DISPLAY INVISIBLE (-1420 2880);
FORCEADD OFFPAGE..4
(-1375 2250);
FORCEPROP 2 LAST $XR0 189 
J 0
(-1099 2250);
DISPLAY 0.638298 (-1099 2250);
PAINT MONO (-1099 2250);
FORCEPROP 2 LAST CDS_LIB mstr_standard
J 0
(-1375 2250);
PAINT ORANGE (-1375 2250);
DISPLAY INVISIBLE (-1375 2250);
FORCEPROP 2 LAST PATH I16
J 0
(-1175 2300);
DISPLAY 1.021277 (-1175 2300);
PAINT ORANGE (-1175 2300);
DISPLAY INVISIBLE (-1175 2300);
FORCEPROP 1 LAST OFFPAGE TRUE
J 0
(-1050 2125);
DISPLAY 0.872340 (-1050 2125);
PAINT GREEN (-1050 2125);
DISPLAY INVISIBLE (-1050 2125);
FORCEPROP 1 LAST COMMENT_BODY TRUE
J 0
(-1400 2150);
DISPLAY 0.872340 (-1400 2150);
PAINT GREEN (-1400 2150);
DISPLAY INVISIBLE (-1400 2150);
FORCEADD RES..1
(-2100 4050);
FORCEPROP 1 LAST PACK_TYPE 0402
J 0
(-2000 4000);
DISPLAY 0.617021 (-2000 4000);
PAINT SKYBLUE (-2000 4000);
FORCEPROP 1 LASTPIN (-2000 4050) $PN 2
J 0
(-2038 4062);
DISPLAY 0.617021 (-2038 4062);
PAINT ORANGE (-2038 4062);
FORCEPROP 1 LAST LOCATION R8G8
J 0
(-2150 4100);
DISPLAY 0.617021 (-2150 4100);
PAINT AQUA (-2150 4100);
FORCEPROP 1 LAST MATERIAL CHIP
J 0
(-2150 4000);
DISPLAY 0.617021 (-2150 4000);
PAINT SKYBLUE (-2150 4000);
FORCEPROP 1 LASTPIN (-2200 4050) $PN 1
J 0
(-2188 4062);
DISPLAY 0.617021 (-2188 4062);
PAINT ORANGE (-2188 4062);
FORCEPROP 1 LAST TOLERANCE 5%
J 0
(-2250 4050);
DISPLAY 0.617021 (-2250 4050);
PAINT SKYBLUE (-2250 4050);
FORCEPROP 1 LAST WATTAGE 1/16W
J 2
(-2175 4000);
DISPLAY 0.617021 (-2175 4000);
PAINT SKYBLUE (-2175 4000);
FORCEPROP 1 LAST VALUE 0.0
J 2
(-2275 4050);
DISPLAY 0.617021 (-2275 4050);
PAINT SKYBLUE (-2275 4050);
FORCEPROP 1 LAST PART_NUMBER G21497-005
J 0
(-1950 4050);
DISPLAY 0.617021 (-1950 4050);
PAINT BLUE (-1950 4050);
FORCEPROP 2 LAST SEC_TYPE 0402
J 0
(-2150 4250);
DISPLAY 1.021277 (-2150 4250);
PAINT ORANGE (-2150 4250);
DISPLAY INVISIBLE (-2150 4250);
FORCEPROP 2 LAST BOM_COST DEBUG
J 0
(-2150 4200);
DISPLAY 1.021277 (-2150 4200);
PAINT ORANGE (-2150 4200);
DISPLAY INVISIBLE (-2150 4200);
FORCEPROP 2 LAST SEC 1
J 0
(-2150 4250);
DISPLAY 0.680851 (-2150 4250);
PAINT MONO (-2150 4250);
DISPLAY INVISIBLE (-2150 4250);
FORCEPROP 1 LAST PATH I17
J 0
(-2150 4200);
DISPLAY 0.978723 (-2150 4200);
PAINT WHITE (-2150 4200);
DISPLAY INVISIBLE (-2150 4200);
FORCEPROP 2 LAST CDS_LIB mstr_discrete
J 0
(-2100 4050);
PAINT ORANGE (-2100 4050);
DISPLAY INVISIBLE (-2100 4050);
FORCEPROP 2 LAST CDS_LOCATION R8G8
J 0
(-2150 4100);
DISPLAY 0.617021 (-2150 4100);
PAINT AQUA (-2150 4100);
DISPLAY INVISIBLE (-2150 4100);
FORCEPROP 2 LAST ROOM BMC_DEBUG_HEADER
J 0
(-2150 4150);
DISPLAY 1.021277 (-2150 4150);
PAINT ORANGE (-2150 4150);
DISPLAY INVISIBLE (-2150 4150);
FORCEADD RES..1
(-125 4650);
FORCEPROP 1 LASTPIN (-225 4650) $PN 1
J 0
(-213 4662);
DISPLAY 0.617021 (-213 4662);
PAINT ORANGE (-213 4662);
FORCEPROP 1 LAST MATERIAL CHIP
J 0
(-150 4600);
DISPLAY 0.617021 (-150 4600);
PAINT SKYBLUE (-150 4600);
FORCEPROP 1 LAST PACK_TYPE 0402
J 0
(-50 4600);
DISPLAY 0.617021 (-50 4600);
PAINT SKYBLUE (-50 4600);
FORCEPROP 1 LASTPIN (-25 4650) $PN 2
J 0
(-63 4662);
DISPLAY 0.617021 (-63 4662);
PAINT ORANGE (-63 4662);
FORCEPROP 1 LAST TOLERANCE 5%
J 0
(-275 4650);
DISPLAY 0.617021 (-275 4650);
PAINT SKYBLUE (-275 4650);
FORCEPROP 1 LAST WATTAGE 1/16W
J 2
(-175 4600);
DISPLAY 0.617021 (-175 4600);
PAINT SKYBLUE (-175 4600);
FORCEPROP 1 LAST PART_NUMBER G21497-005
J 0
(-200 4750);
DISPLAY 0.617021 (-200 4750);
PAINT BLUE (-200 4750);
FORCEPROP 1 LAST LOCATION R8G7
J 0
(-175 4700);
DISPLAY 0.617021 (-175 4700);
PAINT AQUA (-175 4700);
FORCEPROP 1 LAST VALUE 0.0
J 2
(-300 4650);
DISPLAY 0.617021 (-300 4650);
PAINT SKYBLUE (-300 4650);
FORCEPROP 2 LAST SEC 1
J 0
(-175 4850);
DISPLAY 0.680851 (-175 4850);
PAINT MONO (-175 4850);
DISPLAY INVISIBLE (-175 4850);
FORCEPROP 2 LAST SEC_TYPE 0402
J 0
(-175 4850);
DISPLAY 1.021277 (-175 4850);
PAINT ORANGE (-175 4850);
DISPLAY INVISIBLE (-175 4850);
FORCEPROP 2 LAST ROOM BMC_DEBUG_HEADER
J 0
(-175 4750);
DISPLAY 1.021277 (-175 4750);
PAINT ORANGE (-175 4750);
DISPLAY INVISIBLE (-175 4750);
FORCEPROP 1 LAST PATH I18
J 0
(-175 4800);
DISPLAY 0.978723 (-175 4800);
PAINT WHITE (-175 4800);
DISPLAY INVISIBLE (-175 4800);
FORCEPROP 2 LAST BOM_COST DEBUG
J 0
(-175 4800);
DISPLAY 1.021277 (-175 4800);
PAINT ORANGE (-175 4800);
DISPLAY INVISIBLE (-175 4800);
FORCEPROP 2 LAST CDS_LOCATION R8G7
J 0
(-175 4700);
DISPLAY 0.617021 (-175 4700);
PAINT AQUA (-175 4700);
DISPLAY INVISIBLE (-175 4700);
FORCEPROP 2 LAST CDS_LIB mstr_discrete
J 0
(-125 4650);
PAINT ORANGE (-125 4650);
DISPLAY INVISIBLE (-125 4650);
FORCEADD RES..1
(-2100 3500);
FORCEPROP 1 LAST PART_NUMBER G21497-005
J 0
(-1950 3500);
DISPLAY 0.617021 (-1950 3500);
PAINT BLUE (-1950 3500);
FORCEPROP 1 LAST LOCATION R8G11
J 0
(-2150 3550);
DISPLAY 0.617021 (-2150 3550);
PAINT AQUA (-2150 3550);
FORCEPROP 1 LAST PACK_TYPE 0402
J 0
(-2000 3450);
DISPLAY 0.617021 (-2000 3450);
PAINT SKYBLUE (-2000 3450);
FORCEPROP 1 LAST WATTAGE 1/16W
J 2
(-2175 3450);
DISPLAY 0.617021 (-2175 3450);
PAINT SKYBLUE (-2175 3450);
FORCEPROP 1 LASTPIN (-2000 3500) $PN 2
J 0
(-2038 3512);
DISPLAY 0.617021 (-2038 3512);
PAINT ORANGE (-2038 3512);
FORCEPROP 1 LAST MATERIAL EMPTY
J 0
(-2150 3450);
DISPLAY 0.617021 (-2150 3450);
PAINT RED (-2150 3450);
FORCEPROP 1 LASTPIN (-2200 3500) $PN 1
J 0
(-2188 3512);
DISPLAY 0.617021 (-2188 3512);
PAINT ORANGE (-2188 3512);
FORCEPROP 1 LAST TOLERANCE 5%
J 0
(-2250 3500);
DISPLAY 0.617021 (-2250 3500);
PAINT SKYBLUE (-2250 3500);
FORCEPROP 1 LAST VALUE 0.0
J 2
(-2275 3500);
DISPLAY 0.617021 (-2275 3500);
PAINT SKYBLUE (-2275 3500);
FORCEPROP 2 LAST SEC_TYPE 0402
J 0
(-2150 3700);
DISPLAY 1.021277 (-2150 3700);
PAINT ORANGE (-2150 3700);
DISPLAY INVISIBLE (-2150 3700);
FORCEPROP 2 LAST SEC 1
J 0
(-2150 3700);
PAINT MONO (-2150 3700);
DISPLAY INVISIBLE (-2150 3700);
FORCEPROP 2 LAST BOM_COST DEBUG
J 0
(-2150 3650);
DISPLAY 1.021277 (-2150 3650);
PAINT ORANGE (-2150 3650);
DISPLAY INVISIBLE (-2150 3650);
FORCEPROP 1 LAST PATH I19
J 0
(-2150 3650);
DISPLAY 0.978723 (-2150 3650);
PAINT WHITE (-2150 3650);
DISPLAY INVISIBLE (-2150 3650);
FORCEPROP 2 LAST CDS_LIB mstr_discrete
J 0
(-2100 3500);
PAINT MONO (-2100 3500);
DISPLAY INVISIBLE (-2100 3500);
FORCEPROP 2 LAST ROOM BMC_DEBUG_HEADER
J 0
(-2150 3600);
DISPLAY 1.021277 (-2150 3600);
PAINT ORANGE (-2150 3600);
DISPLAY INVISIBLE (-2150 3600);
FORCEPROP 2 LAST CDS_LOCATION R8G11
J 0
(-2150 3550);
DISPLAY 0.617021 (-2150 3550);
PAINT AQUA (-2150 3550);
DISPLAY INVISIBLE (-2150 3550);
FORCEADD OFFPAGE..1
(-750 4450);
FORCEPROP 2 LAST $XR0 191 
J 0
(-1212 4450);
DISPLAY 0.638298 (-1212 4450);
PAINT MONO (-1212 4450);
FORCEPROP 2 LAST PATH I2
J 0
(-1025 4500);
DISPLAY 1.021277 (-1025 4500);
PAINT ORANGE (-1025 4500);
DISPLAY INVISIBLE (-1025 4500);
FORCEPROP 1 LAST COMMENT_BODY TRUE
J 0
(-625 4350);
DISPLAY 0.872340 (-625 4350);
PAINT GREEN (-625 4350);
DISPLAY INVISIBLE (-625 4350);
FORCEPROP 1 LAST OFFPAGE TRUE
J 0
(-425 4325);
DISPLAY 0.872340 (-425 4325);
PAINT GREEN (-425 4325);
DISPLAY INVISIBLE (-425 4325);
FORCEPROP 2 LAST CDS_LIB mstr_standard
J 0
(-750 4450);
PAINT ORANGE (-750 4450);
DISPLAY INVISIBLE (-750 4450);
FORCEADD RES..1
(-2100 3350);
FORCEPROP 1 LAST PART_NUMBER G21497-005
J 0
(-1950 3350);
DISPLAY 0.617021 (-1950 3350);
PAINT BLUE (-1950 3350);
FORCEPROP 1 LAST PACK_TYPE 0402
J 0
(-2000 3300);
DISPLAY 0.617021 (-2000 3300);
PAINT SKYBLUE (-2000 3300);
FORCEPROP 1 LAST MATERIAL CHIP
J 0
(-2125 3300);
DISPLAY 0.617021 (-2125 3300);
PAINT SKYBLUE (-2125 3300);
FORCEPROP 1 LAST LOCATION R8G14
J 0
(-2150 3400);
DISPLAY 0.617021 (-2150 3400);
PAINT AQUA (-2150 3400);
FORCEPROP 1 LASTPIN (-2000 3350) $PN 2
J 0
(-2038 3362);
DISPLAY 0.617021 (-2038 3362);
PAINT ORANGE (-2038 3362);
FORCEPROP 1 LAST TOLERANCE 5%
J 0
(-2250 3350);
DISPLAY 0.617021 (-2250 3350);
PAINT SKYBLUE (-2250 3350);
FORCEPROP 1 LASTPIN (-2200 3350) $PN 1
J 0
(-2188 3362);
DISPLAY 0.617021 (-2188 3362);
PAINT ORANGE (-2188 3362);
FORCEPROP 1 LAST WATTAGE 1/16W
J 2
(-2175 3300);
DISPLAY 0.617021 (-2175 3300);
PAINT SKYBLUE (-2175 3300);
FORCEPROP 1 LAST VALUE 0.0
J 2
(-2275 3350);
DISPLAY 0.617021 (-2275 3350);
PAINT SKYBLUE (-2275 3350);
FORCEPROP 2 LAST SEC_TYPE 0402
J 0
(-2150 3550);
DISPLAY 1.021277 (-2150 3550);
PAINT ORANGE (-2150 3550);
DISPLAY INVISIBLE (-2150 3550);
FORCEPROP 2 LAST SEC 1
J 0
(-2150 3550);
DISPLAY 0.680851 (-2150 3550);
PAINT MONO (-2150 3550);
DISPLAY INVISIBLE (-2150 3550);
FORCEPROP 2 LAST ROOM BMC_DEBUG_HEADER
J 0
(-2150 3450);
DISPLAY 1.021277 (-2150 3450);
PAINT ORANGE (-2150 3450);
DISPLAY INVISIBLE (-2150 3450);
FORCEPROP 1 LAST PATH I20
J 0
(-2150 3500);
DISPLAY 0.978723 (-2150 3500);
PAINT WHITE (-2150 3500);
DISPLAY INVISIBLE (-2150 3500);
FORCEPROP 2 LAST BOM_COST DEBUG
J 0
(-2150 3500);
DISPLAY 1.021277 (-2150 3500);
PAINT ORANGE (-2150 3500);
DISPLAY INVISIBLE (-2150 3500);
FORCEPROP 2 LAST CDS_LIB mstr_discrete
J 0
(-2100 3350);
PAINT ORANGE (-2100 3350);
DISPLAY INVISIBLE (-2100 3350);
FORCEPROP 2 LAST CDS_LOCATION R8G14
J 0
(-2150 3400);
DISPLAY 0.617021 (-2150 3400);
PAINT AQUA (-2150 3400);
DISPLAY INVISIBLE (-2150 3400);
FORCEADD RES..1
(-2100 3675);
FORCEPROP 1 LAST LOCATION R8G12
J 0
(-2150 3725);
DISPLAY 0.617021 (-2150 3725);
PAINT AQUA (-2150 3725);
FORCEPROP 1 LAST PART_NUMBER G21497-005
J 0
(-1950 3675);
DISPLAY 0.617021 (-1950 3675);
PAINT BLUE (-1950 3675);
FORCEPROP 1 LASTPIN (-2000 3675) $PN 2
J 0
(-2038 3687);
DISPLAY 0.617021 (-2038 3687);
PAINT ORANGE (-2038 3687);
FORCEPROP 1 LASTPIN (-2200 3675) $PN 1
J 0
(-2188 3687);
DISPLAY 0.617021 (-2188 3687);
PAINT ORANGE (-2188 3687);
FORCEPROP 1 LAST MATERIAL EMPTY
J 0
(-2150 3625);
DISPLAY 0.617021 (-2150 3625);
PAINT RED (-2150 3625);
FORCEPROP 1 LAST TOLERANCE 5%
J 0
(-2250 3675);
DISPLAY 0.617021 (-2250 3675);
PAINT SKYBLUE (-2250 3675);
FORCEPROP 1 LAST WATTAGE 1/16W
J 2
(-2175 3625);
DISPLAY 0.617021 (-2175 3625);
PAINT SKYBLUE (-2175 3625);
FORCEPROP 1 LAST VALUE 0.0
J 2
(-2275 3675);
DISPLAY 0.617021 (-2275 3675);
PAINT SKYBLUE (-2275 3675);
FORCEPROP 1 LAST PACK_TYPE 0402
J 0
(-2000 3625);
DISPLAY 0.617021 (-2000 3625);
PAINT SKYBLUE (-2000 3625);
FORCEPROP 1 LAST PATH I21
J 0
(-2150 3825);
DISPLAY 0.978723 (-2150 3825);
PAINT WHITE (-2150 3825);
DISPLAY INVISIBLE (-2150 3825);
FORCEPROP 2 LAST SEC_TYPE 0402
J 0
(-2150 3875);
DISPLAY 1.021277 (-2150 3875);
PAINT ORANGE (-2150 3875);
DISPLAY INVISIBLE (-2150 3875);
FORCEPROP 2 LAST SEC 1
J 0
(-2150 3875);
DISPLAY 0.680851 (-2150 3875);
PAINT MONO (-2150 3875);
DISPLAY INVISIBLE (-2150 3875);
FORCEPROP 2 LAST BOM_COST DEBUG
J 0
(-2150 3825);
DISPLAY 1.021277 (-2150 3825);
PAINT ORANGE (-2150 3825);
DISPLAY INVISIBLE (-2150 3825);
FORCEPROP 2 LAST ROOM BMC_DEBUG_HEADER
J 0
(-2150 3775);
DISPLAY 1.021277 (-2150 3775);
PAINT ORANGE (-2150 3775);
DISPLAY INVISIBLE (-2150 3775);
FORCEPROP 2 LAST CDS_LOCATION R8G12
J 0
(-2150 3725);
DISPLAY 0.617021 (-2150 3725);
PAINT AQUA (-2150 3725);
DISPLAY INVISIBLE (-2150 3725);
FORCEPROP 2 LAST CDS_LIB mstr_discrete
J 0
(-2100 3675);
PAINT ORANGE (-2100 3675);
DISPLAY INVISIBLE (-2100 3675);
FORCEADD RES..1
(-2100 2800);
FORCEPROP 1 LAST PART_NUMBER G21497-005
J 0
(-1950 2800);
DISPLAY 0.617021 (-1950 2800);
PAINT BLUE (-1950 2800);
FORCEPROP 1 LAST PACK_TYPE 0402
J 0
(-2000 2750);
DISPLAY 0.617021 (-2000 2750);
PAINT SKYBLUE (-2000 2750);
FORCEPROP 1 LASTPIN (-2000 2800) $PN 2
J 0
(-2038 2812);
DISPLAY 0.617021 (-2038 2812);
PAINT ORANGE (-2038 2812);
FORCEPROP 1 LAST MATERIAL EMPTY
J 0
(-2150 2750);
DISPLAY 0.617021 (-2150 2750);
PAINT RED (-2150 2750);
FORCEPROP 1 LAST LOCATION R8G16
J 0
(-2150 2850);
DISPLAY 0.617021 (-2150 2850);
PAINT AQUA (-2150 2850);
FORCEPROP 1 LASTPIN (-2200 2800) $PN 1
J 0
(-2188 2812);
DISPLAY 0.617021 (-2188 2812);
PAINT ORANGE (-2188 2812);
FORCEPROP 1 LAST TOLERANCE 5%
J 0
(-2250 2800);
DISPLAY 0.617021 (-2250 2800);
PAINT SKYBLUE (-2250 2800);
FORCEPROP 1 LAST WATTAGE 1/16W
J 2
(-2175 2750);
DISPLAY 0.617021 (-2175 2750);
PAINT SKYBLUE (-2175 2750);
FORCEPROP 1 LAST VALUE 0.0
J 2
(-2275 2800);
DISPLAY 0.617021 (-2275 2800);
PAINT SKYBLUE (-2275 2800);
FORCEPROP 2 LAST BOM_COST DEBUG
J 0
(-2150 2950);
DISPLAY 1.021277 (-2150 2950);
PAINT ORANGE (-2150 2950);
DISPLAY INVISIBLE (-2150 2950);
FORCEPROP 2 LAST SEC_TYPE 0402
J 0
(-2150 3000);
DISPLAY 1.021277 (-2150 3000);
PAINT ORANGE (-2150 3000);
DISPLAY INVISIBLE (-2150 3000);
FORCEPROP 2 LAST SEC 1
J 0
(-2150 3000);
PAINT MONO (-2150 3000);
DISPLAY INVISIBLE (-2150 3000);
FORCEPROP 1 LAST PATH I22
J 0
(-2150 2950);
DISPLAY 0.978723 (-2150 2950);
PAINT WHITE (-2150 2950);
DISPLAY INVISIBLE (-2150 2950);
FORCEPROP 2 LAST ROOM BMC_DEBUG_HEADER
J 0
(-2150 2900);
DISPLAY 1.021277 (-2150 2900);
PAINT ORANGE (-2150 2900);
DISPLAY INVISIBLE (-2150 2900);
FORCEPROP 2 LAST CDS_LIB mstr_discrete
J 0
(-2100 2800);
PAINT MONO (-2100 2800);
DISPLAY INVISIBLE (-2100 2800);
FORCEPROP 2 LAST CDS_LOCATION R8G16
J 0
(-2150 2850);
DISPLAY 0.617021 (-2150 2850);
PAINT AQUA (-2150 2850);
DISPLAY INVISIBLE (-2150 2850);
FORCEADD RES..1
(-125 4450);
FORCEPROP 1 LASTPIN (-25 4450) $PN 2
J 0
(-63 4462);
DISPLAY 0.617021 (-63 4462);
PAINT ORANGE (-63 4462);
FORCEPROP 1 LAST VALUE 0.0
J 2
(-300 4450);
DISPLAY 0.617021 (-300 4450);
PAINT SKYBLUE (-300 4450);
FORCEPROP 1 LAST PART_NUMBER G21497-005
J 0
(-200 4550);
DISPLAY 0.617021 (-200 4550);
PAINT BLUE (-200 4550);
FORCEPROP 1 LAST LOCATION R8G13
J 0
(-175 4500);
DISPLAY 0.617021 (-175 4500);
PAINT AQUA (-175 4500);
FORCEPROP 1 LASTPIN (-225 4450) $PN 1
J 0
(-213 4462);
DISPLAY 0.617021 (-213 4462);
PAINT ORANGE (-213 4462);
FORCEPROP 1 LAST TOLERANCE 5%
J 0
(-275 4450);
DISPLAY 0.617021 (-275 4450);
PAINT SKYBLUE (-275 4450);
FORCEPROP 1 LAST WATTAGE 1/16W
J 2
(-175 4400);
DISPLAY 0.617021 (-175 4400);
PAINT SKYBLUE (-175 4400);
FORCEPROP 1 LAST MATERIAL CHIP
J 0
(-150 4400);
DISPLAY 0.617021 (-150 4400);
PAINT SKYBLUE (-150 4400);
FORCEPROP 1 LAST PACK_TYPE 0402
J 0
(-50 4400);
DISPLAY 0.617021 (-50 4400);
PAINT SKYBLUE (-50 4400);
FORCEPROP 2 LAST CDS_LOCATION R8G13
J 0
(-175 4500);
DISPLAY 0.617021 (-175 4500);
PAINT AQUA (-175 4500);
DISPLAY INVISIBLE (-175 4500);
FORCEPROP 2 LAST ROOM BMC_DEBUG_HEADER
J 0
(-175 4550);
DISPLAY 1.021277 (-175 4550);
PAINT ORANGE (-175 4550);
DISPLAY INVISIBLE (-175 4550);
FORCEPROP 2 LAST SEC_TYPE 0402
J 0
(-175 4650);
DISPLAY 1.021277 (-175 4650);
PAINT ORANGE (-175 4650);
DISPLAY INVISIBLE (-175 4650);
FORCEPROP 2 LAST SEC 1
J 0
(-175 4650);
DISPLAY 0.680851 (-175 4650);
PAINT MONO (-175 4650);
DISPLAY INVISIBLE (-175 4650);
FORCEPROP 1 LAST PATH I23
J 0
(-175 4600);
DISPLAY 0.978723 (-175 4600);
PAINT WHITE (-175 4600);
DISPLAY INVISIBLE (-175 4600);
FORCEPROP 2 LAST BOM_COST DEBUG
J 0
(-175 4600);
DISPLAY 1.021277 (-175 4600);
PAINT ORANGE (-175 4600);
DISPLAY INVISIBLE (-175 4600);
FORCEPROP 2 LAST CDS_LIB mstr_discrete
J 0
(-125 4450);
PAINT ORANGE (-125 4450);
DISPLAY INVISIBLE (-125 4450);
FORCEADD RES..1
(-2100 2975);
FORCEPROP 1 LAST PART_NUMBER G21497-005
J 0
(-1950 2975);
DISPLAY 0.617021 (-1950 2975);
PAINT BLUE (-1950 2975);
FORCEPROP 1 LAST PACK_TYPE 0402
J 0
(-2000 2925);
DISPLAY 0.617021 (-2000 2925);
PAINT SKYBLUE (-2000 2925);
FORCEPROP 1 LAST VALUE 0.0
J 2
(-2275 2975);
DISPLAY 0.617021 (-2275 2975);
PAINT SKYBLUE (-2275 2975);
FORCEPROP 1 LASTPIN (-2000 2975) $PN 2
J 0
(-2038 2987);
DISPLAY 0.617021 (-2038 2987);
PAINT ORANGE (-2038 2987);
FORCEPROP 1 LAST MATERIAL EMPTY
J 0
(-2150 2925);
DISPLAY 0.617021 (-2150 2925);
PAINT RED (-2150 2925);
FORCEPROP 1 LAST LOCATION R8G15
J 0
(-2150 3025);
DISPLAY 0.617021 (-2150 3025);
PAINT AQUA (-2150 3025);
FORCEPROP 1 LASTPIN (-2200 2975) $PN 1
J 0
(-2188 2987);
DISPLAY 0.617021 (-2188 2987);
PAINT ORANGE (-2188 2987);
FORCEPROP 1 LAST TOLERANCE 5%
J 0
(-2250 2975);
DISPLAY 0.617021 (-2250 2975);
PAINT SKYBLUE (-2250 2975);
FORCEPROP 1 LAST WATTAGE 1/16W
J 2
(-2175 2925);
DISPLAY 0.617021 (-2175 2925);
PAINT SKYBLUE (-2175 2925);
FORCEPROP 2 LAST SEC 1
J 0
(-2150 3175);
DISPLAY 0.680851 (-2150 3175);
PAINT MONO (-2150 3175);
DISPLAY INVISIBLE (-2150 3175);
FORCEPROP 2 LAST SEC_TYPE 0402
J 0
(-2150 3175);
DISPLAY 1.021277 (-2150 3175);
PAINT ORANGE (-2150 3175);
DISPLAY INVISIBLE (-2150 3175);
FORCEPROP 2 LAST CDS_LIB mstr_discrete
J 0
(-2100 2975);
PAINT ORANGE (-2100 2975);
DISPLAY INVISIBLE (-2100 2975);
FORCEPROP 2 LAST BOM_COST DEBUG
J 0
(-2150 3125);
DISPLAY 1.021277 (-2150 3125);
PAINT ORANGE (-2150 3125);
DISPLAY INVISIBLE (-2150 3125);
FORCEPROP 1 LAST PATH I24
J 0
(-2150 3125);
DISPLAY 0.978723 (-2150 3125);
PAINT WHITE (-2150 3125);
DISPLAY INVISIBLE (-2150 3125);
FORCEPROP 2 LAST ROOM BMC_DEBUG_HEADER
J 0
(-2150 3075);
DISPLAY 1.021277 (-2150 3075);
PAINT ORANGE (-2150 3075);
DISPLAY INVISIBLE (-2150 3075);
FORCEPROP 2 LAST CDS_LOCATION R8G15
J 0
(-2150 3025);
DISPLAY 0.617021 (-2150 3025);
PAINT AQUA (-2150 3025);
DISPLAY INVISIBLE (-2150 3025);
FORCEADD RES..1
(-2100 2625);
FORCEPROP 1 LAST PART_NUMBER G21497-005
J 0
(-1950 2625);
DISPLAY 0.617021 (-1950 2625);
PAINT BLUE (-1950 2625);
FORCEPROP 1 LAST LOCATION R8G17
J 0
(-2150 2675);
DISPLAY 0.617021 (-2150 2675);
PAINT AQUA (-2150 2675);
FORCEPROP 1 LASTPIN (-2000 2625) $PN 2
J 0
(-2038 2637);
DISPLAY 0.617021 (-2038 2637);
PAINT ORANGE (-2038 2637);
FORCEPROP 1 LASTPIN (-2200 2625) $PN 1
J 0
(-2188 2637);
DISPLAY 0.617021 (-2188 2637);
PAINT ORANGE (-2188 2637);
FORCEPROP 1 LAST PACK_TYPE 0402
J 0
(-2025 2575);
DISPLAY 0.617021 (-2025 2575);
PAINT SKYBLUE (-2025 2575);
FORCEPROP 1 LAST MATERIAL CHIP
J 0
(-2150 2575);
DISPLAY 0.617021 (-2150 2575);
PAINT SKYBLUE (-2150 2575);
FORCEPROP 1 LAST TOLERANCE 5%
J 0
(-2250 2625);
DISPLAY 0.617021 (-2250 2625);
PAINT SKYBLUE (-2250 2625);
FORCEPROP 1 LAST WATTAGE 1/16W
J 2
(-2175 2575);
DISPLAY 0.617021 (-2175 2575);
PAINT SKYBLUE (-2175 2575);
FORCEPROP 1 LAST VALUE 0.0
J 2
(-2275 2625);
DISPLAY 0.617021 (-2275 2625);
PAINT SKYBLUE (-2275 2625);
FORCEPROP 2 LAST SEC_TYPE 0402
J 0
(-2150 2825);
DISPLAY 1.021277 (-2150 2825);
PAINT ORANGE (-2150 2825);
DISPLAY INVISIBLE (-2150 2825);
FORCEPROP 2 LAST SEC 1
J 0
(-2150 2825);
DISPLAY 0.680851 (-2150 2825);
PAINT MONO (-2150 2825);
DISPLAY INVISIBLE (-2150 2825);
FORCEPROP 2 LAST BOM_COST DEBUG
J 0
(-2150 2775);
DISPLAY 1.021277 (-2150 2775);
PAINT ORANGE (-2150 2775);
DISPLAY INVISIBLE (-2150 2775);
FORCEPROP 1 LAST PATH I25
J 0
(-2150 2775);
DISPLAY 0.978723 (-2150 2775);
PAINT WHITE (-2150 2775);
DISPLAY INVISIBLE (-2150 2775);
FORCEPROP 2 LAST CDS_LOCATION R8G17
J 0
(-2150 2675);
DISPLAY 0.617021 (-2150 2675);
PAINT AQUA (-2150 2675);
DISPLAY INVISIBLE (-2150 2675);
FORCEPROP 2 LAST ROOM BMC_DEBUG_HEADER
J 0
(-2150 2725);
DISPLAY 1.021277 (-2150 2725);
PAINT ORANGE (-2150 2725);
DISPLAY INVISIBLE (-2150 2725);
FORCEPROP 2 LAST CDS_LIB mstr_discrete
J 0
(-2100 2625);
PAINT ORANGE (-2100 2625);
DISPLAY INVISIBLE (-2100 2625);
FORCEADD RES..1
(-125 4250);
FORCEPROP 1 LAST TOLERANCE 5%
J 0
(-275 4250);
DISPLAY 0.617021 (-275 4250);
PAINT SKYBLUE (-275 4250);
FORCEPROP 1 LASTPIN (-25 4250) $PN 2
J 0
(-63 4262);
DISPLAY 0.617021 (-63 4262);
PAINT ORANGE (-63 4262);
FORCEPROP 1 LASTPIN (-225 4250) $PN 1
J 0
(-213 4262);
DISPLAY 0.617021 (-213 4262);
PAINT ORANGE (-213 4262);
FORCEPROP 1 LAST PART_NUMBER G21497-005
J 0
(-225 4325);
DISPLAY 0.617021 (-225 4325);
PAINT BLUE (-225 4325);
FORCEPROP 1 LAST LOCATION R8G18
J 0
(-175 4300);
DISPLAY 0.617021 (-175 4300);
PAINT AQUA (-175 4300);
FORCEPROP 1 LAST VALUE 0.0
J 2
(-300 4250);
DISPLAY 0.617021 (-300 4250);
PAINT SKYBLUE (-300 4250);
FORCEPROP 1 LAST WATTAGE 1/16W
J 2
(-175 4200);
DISPLAY 0.617021 (-175 4200);
PAINT SKYBLUE (-175 4200);
FORCEPROP 1 LAST MATERIAL CHIP
J 0
(-150 4200);
DISPLAY 0.617021 (-150 4200);
PAINT SKYBLUE (-150 4200);
FORCEPROP 1 LAST PACK_TYPE 0402
J 0
(-50 4200);
DISPLAY 0.617021 (-50 4200);
PAINT SKYBLUE (-50 4200);
FORCEPROP 2 LAST SEC_TYPE 0402
J 0
(-175 4450);
DISPLAY 1.021277 (-175 4450);
PAINT ORANGE (-175 4450);
DISPLAY INVISIBLE (-175 4450);
FORCEPROP 2 LAST SEC 1
J 0
(-175 4450);
DISPLAY 0.680851 (-175 4450);
PAINT MONO (-175 4450);
DISPLAY INVISIBLE (-175 4450);
FORCEPROP 2 LAST CDS_LIB mstr_discrete
J 0
(-125 4250);
PAINT ORANGE (-125 4250);
DISPLAY INVISIBLE (-125 4250);
FORCEPROP 2 LAST ROOM BMC_DEBUG_HEADER
J 0
(-175 4350);
DISPLAY 1.021277 (-175 4350);
PAINT ORANGE (-175 4350);
DISPLAY INVISIBLE (-175 4350);
FORCEPROP 1 LAST PATH I26
J 0
(-175 4400);
DISPLAY 0.978723 (-175 4400);
PAINT WHITE (-175 4400);
DISPLAY INVISIBLE (-175 4400);
FORCEPROP 2 LAST BOM_COST DEBUG
J 0
(-175 4400);
DISPLAY 1.021277 (-175 4400);
PAINT ORANGE (-175 4400);
DISPLAY INVISIBLE (-175 4400);
FORCEPROP 2 LAST CDS_LOCATION R8G18
J 0
(-175 4300);
DISPLAY 0.617021 (-175 4300);
PAINT AQUA (-175 4300);
DISPLAY INVISIBLE (-175 4300);
FORCEADD RES..1
(-2100 2250);
FORCEPROP 1 LAST PART_NUMBER G21497-005
J 0
(-1950 2250);
DISPLAY 0.617021 (-1950 2250);
PAINT BLUE (-1950 2250);
FORCEPROP 1 LAST PACK_TYPE 0402
J 0
(-2000 2200);
DISPLAY 0.617021 (-2000 2200);
PAINT SKYBLUE (-2000 2200);
FORCEPROP 1 LASTPIN (-2000 2250) $PN 2
J 0
(-2038 2262);
DISPLAY 0.617021 (-2038 2262);
PAINT ORANGE (-2038 2262);
FORCEPROP 1 LAST MATERIAL EMPTY
J 0
(-2150 2200);
DISPLAY 0.617021 (-2150 2200);
PAINT RED (-2150 2200);
FORCEPROP 1 LAST LOCATION R7G16
J 0
(-2150 2300);
DISPLAY 0.617021 (-2150 2300);
PAINT AQUA (-2150 2300);
FORCEPROP 1 LASTPIN (-2200 2250) $PN 1
J 0
(-2188 2262);
DISPLAY 0.617021 (-2188 2262);
PAINT ORANGE (-2188 2262);
FORCEPROP 1 LAST TOLERANCE 5%
J 0
(-2250 2250);
DISPLAY 0.617021 (-2250 2250);
PAINT SKYBLUE (-2250 2250);
FORCEPROP 1 LAST WATTAGE 1/16W
J 2
(-2175 2200);
DISPLAY 0.617021 (-2175 2200);
PAINT SKYBLUE (-2175 2200);
FORCEPROP 1 LAST VALUE 0.0
J 2
(-2275 2250);
DISPLAY 0.617021 (-2275 2250);
PAINT SKYBLUE (-2275 2250);
FORCEPROP 2 LAST SEC 1
J 0
(-2150 2450);
DISPLAY 0.680851 (-2150 2450);
PAINT MONO (-2150 2450);
DISPLAY INVISIBLE (-2150 2450);
FORCEPROP 2 LAST SEC_TYPE 0402
J 0
(-2150 2450);
DISPLAY 1.021277 (-2150 2450);
PAINT ORANGE (-2150 2450);
DISPLAY INVISIBLE (-2150 2450);
FORCEPROP 2 LAST BOM_COST DEBUG
J 0
(-2150 2400);
DISPLAY 1.021277 (-2150 2400);
PAINT ORANGE (-2150 2400);
DISPLAY INVISIBLE (-2150 2400);
FORCEPROP 1 LAST PATH I27
J 0
(-2150 2400);
DISPLAY 0.978723 (-2150 2400);
PAINT WHITE (-2150 2400);
DISPLAY INVISIBLE (-2150 2400);
FORCEPROP 2 LAST CDS_LIB mstr_discrete
J 0
(-2100 2250);
PAINT ORANGE (-2100 2250);
DISPLAY INVISIBLE (-2100 2250);
FORCEPROP 2 LAST CDS_LOCATION R7G16
J 0
(-2150 2300);
DISPLAY 0.617021 (-2150 2300);
PAINT AQUA (-2150 2300);
DISPLAY INVISIBLE (-2150 2300);
FORCEPROP 2 LAST ROOM BMC_DEBUG_HEADER
J 0
(-2150 2350);
DISPLAY 1.021277 (-2150 2350);
PAINT ORANGE (-2150 2350);
DISPLAY INVISIBLE (-2150 2350);
FORCEADD OFFPAGE..1
(-2850 4225);
FORCEPROP 2 LAST $XR0 120 
J 0
(-3102 4225);
DISPLAY 0.638298 (-3102 4225);
PAINT MONO (-3102 4225);
FORCEPROP 2 LAST CDS_LIB mstr_standard
J 0
(-2850 4225);
PAINT MONO (-2850 4225);
DISPLAY INVISIBLE (-2850 4225);
FORCEPROP 2 LAST PATH I28
J 0
(-3100 4275);
DISPLAY 1.021277 (-3100 4275);
PAINT ORANGE (-3100 4275);
DISPLAY INVISIBLE (-3100 4275);
FORCEPROP 1 LAST OFFPAGE TRUE
J 0
(-2525 4100);
DISPLAY 0.872340 (-2525 4100);
PAINT GREEN (-2525 4100);
DISPLAY INVISIBLE (-2525 4100);
FORCEPROP 1 LAST COMMENT_BODY TRUE
J 0
(-2725 4125);
DISPLAY 0.872340 (-2725 4125);
PAINT GREEN (-2725 4125);
DISPLAY INVISIBLE (-2725 4125);
FORCEADD OFFPAGE..1
(-750 4650);
FORCEPROP 2 LAST $XR0 191 
J 0
(-1212 4650);
DISPLAY 0.638298 (-1212 4650);
PAINT MONO (-1212 4650);
FORCEPROP 2 LAST CDS_LIB mstr_standard
J 0
(-750 4650);
PAINT ORANGE (-750 4650);
DISPLAY INVISIBLE (-750 4650);
FORCEPROP 2 LAST PATH I29
J 0
(-1025 4700);
DISPLAY 1.021277 (-1025 4700);
PAINT ORANGE (-1025 4700);
DISPLAY INVISIBLE (-1025 4700);
FORCEPROP 1 LAST OFFPAGE TRUE
J 0
(-425 4525);
DISPLAY 0.872340 (-425 4525);
PAINT GREEN (-425 4525);
DISPLAY INVISIBLE (-425 4525);
FORCEPROP 1 LAST COMMENT_BODY TRUE
J 0
(-625 4550);
DISPLAY 0.872340 (-625 4550);
PAINT GREEN (-625 4550);
DISPLAY INVISIBLE (-625 4550);
FORCEADD OFFPAGE..1
(-2850 3350);
FORCEPROP 2 LAST $XR1 255 
J 0
(-3222 3350);
DISPLAY 0.638298 (-3222 3350);
PAINT MONO (-3222 3350);
FORCEPROP 2 LAST $XR0 144 
J 0
(-3102 3350);
DISPLAY 0.638298 (-3102 3350);
PAINT MONO (-3102 3350);
FORCEPROP 2 LAST CDS_LIB mstr_standard
J 0
(-2850 3350);
PAINT ORANGE (-2850 3350);
DISPLAY INVISIBLE (-2850 3350);
FORCEPROP 2 LAST PATH I3
J 0
(-3125 3400);
DISPLAY 1.021277 (-3125 3400);
PAINT ORANGE (-3125 3400);
DISPLAY INVISIBLE (-3125 3400);
FORCEPROP 1 LAST OFFPAGE TRUE
J 0
(-2525 3225);
DISPLAY 0.872340 (-2525 3225);
PAINT GREEN (-2525 3225);
DISPLAY INVISIBLE (-2525 3225);
FORCEPROP 1 LAST COMMENT_BODY TRUE
J 0
(-2725 3250);
DISPLAY 0.872340 (-2725 3250);
PAINT GREEN (-2725 3250);
DISPLAY INVISIBLE (-2725 3250);
FORCEADD OFFPAGE..1
(-2850 4050);
FORCEPROP 2 LAST $XR1 255 
J 0
(-3222 4050);
DISPLAY 0.638298 (-3222 4050);
PAINT MONO (-3222 4050);
FORCEPROP 2 LAST $XR0 144 
J 0
(-3102 4050);
DISPLAY 0.638298 (-3102 4050);
PAINT MONO (-3102 4050);
FORCEPROP 2 LAST CDS_LIB mstr_standard
J 0
(-2850 4050);
PAINT ORANGE (-2850 4050);
DISPLAY INVISIBLE (-2850 4050);
FORCEPROP 2 LAST PATH I30
J 0
(-3100 4100);
DISPLAY 1.021277 (-3100 4100);
PAINT ORANGE (-3100 4100);
DISPLAY INVISIBLE (-3100 4100);
FORCEPROP 1 LAST OFFPAGE TRUE
J 0
(-2525 3925);
DISPLAY 0.872340 (-2525 3925);
PAINT GREEN (-2525 3925);
DISPLAY INVISIBLE (-2525 3925);
FORCEPROP 1 LAST COMMENT_BODY TRUE
J 0
(-2725 3950);
DISPLAY 0.872340 (-2725 3950);
PAINT GREEN (-2725 3950);
DISPLAY INVISIBLE (-2725 3950);
FORCEADD OFFPAGE..1
(-2850 3675);
FORCEPROP 2 LAST $XR0 120 
J 0
(-3102 3675);
DISPLAY 0.638298 (-3102 3675);
PAINT MONO (-3102 3675);
FORCEPROP 2 LAST PATH I31
J 0
(-3125 3725);
DISPLAY 1.021277 (-3125 3725);
PAINT ORANGE (-3125 3725);
DISPLAY INVISIBLE (-3125 3725);
FORCEPROP 2 LAST CDS_LIB mstr_standard
J 0
(-2850 3675);
PAINT ORANGE (-2850 3675);
DISPLAY INVISIBLE (-2850 3675);
FORCEPROP 1 LAST OFFPAGE TRUE
J 0
(-2525 3550);
DISPLAY 0.872340 (-2525 3550);
PAINT GREEN (-2525 3550);
DISPLAY INVISIBLE (-2525 3550);
FORCEPROP 1 LAST COMMENT_BODY TRUE
J 0
(-2725 3575);
DISPLAY 0.872340 (-2725 3575);
PAINT GREEN (-2725 3575);
DISPLAY INVISIBLE (-2725 3575);
FORCEADD OFFPAGE..1
(-2850 2800);
FORCEPROP 2 LAST $XR0 120 
J 0
(-3102 2800);
DISPLAY 0.638298 (-3102 2800);
PAINT MONO (-3102 2800);
FORCEPROP 2 LAST CDS_LIB mstr_standard
J 0
(-2850 2800);
PAINT MONO (-2850 2800);
DISPLAY INVISIBLE (-2850 2800);
FORCEPROP 2 LAST PATH I32
J 0
(-3125 2850);
DISPLAY 1.021277 (-3125 2850);
PAINT ORANGE (-3125 2850);
DISPLAY INVISIBLE (-3125 2850);
FORCEPROP 1 LAST OFFPAGE TRUE
J 0
(-2525 2675);
DISPLAY 0.872340 (-2525 2675);
PAINT GREEN (-2525 2675);
DISPLAY INVISIBLE (-2525 2675);
FORCEPROP 1 LAST COMMENT_BODY TRUE
J 0
(-2725 2700);
DISPLAY 0.872340 (-2725 2700);
PAINT GREEN (-2725 2700);
DISPLAY INVISIBLE (-2725 2700);
FORCEADD OFFPAGE..5
(-2850 2250);
FORCEPROP 2 LAST $XR0 120 
J 0
(-3105 2250);
DISPLAY 0.638298 (-3105 2250);
PAINT MONO (-3105 2250);
FORCEPROP 2 LAST CDS_LIB mstr_standard
J 0
(-2850 2250);
PAINT ORANGE (-2850 2250);
DISPLAY INVISIBLE (-2850 2250);
FORCEPROP 2 LAST PATH I33
J 0
(-3125 2300);
DISPLAY 1.021277 (-3125 2300);
PAINT ORANGE (-3125 2300);
DISPLAY INVISIBLE (-3125 2300);
FORCEPROP 1 LAST OFFPAGE TRUE
J 0
(-2525 2125);
DISPLAY 0.872340 (-2525 2125);
PAINT GREEN (-2525 2125);
DISPLAY INVISIBLE (-2525 2125);
FORCEPROP 1 LAST COMMENT_BODY TRUE
J 0
(-2750 2175);
DISPLAY 0.872340 (-2750 2175);
PAINT GREEN (-2750 2175);
DISPLAY INVISIBLE (-2750 2175);
FORCEADD OFFPAGE..1
(-2850 2625);
FORCEPROP 2 LAST $XR1 254 
J 0
(-3222 2625);
DISPLAY 0.638298 (-3222 2625);
PAINT MONO (-3222 2625);
FORCEPROP 2 LAST $XR0 144 
J 0
(-3102 2625);
DISPLAY 0.638298 (-3102 2625);
PAINT MONO (-3102 2625);
FORCEPROP 2 LAST CDS_LIB mstr_standard
J 0
(-2850 2625);
PAINT ORANGE (-2850 2625);
DISPLAY INVISIBLE (-2850 2625);
FORCEPROP 1 LAST OFFPAGE TRUE
J 0
(-2525 2500);
DISPLAY 0.872340 (-2525 2500);
PAINT GREEN (-2525 2500);
DISPLAY INVISIBLE (-2525 2500);
FORCEPROP 1 LAST COMMENT_BODY TRUE
J 0
(-2725 2525);
DISPLAY 0.872340 (-2725 2525);
PAINT GREEN (-2725 2525);
DISPLAY INVISIBLE (-2725 2525);
FORCEPROP 2 LAST PATH I34
J 0
(-3125 2675);
DISPLAY 1.021277 (-3125 2675);
PAINT ORANGE (-3125 2675);
DISPLAY INVISIBLE (-3125 2675);
FORCEADD OFFPAGE..1
(-750 4250);
FORCEPROP 2 LAST $XR0 191 
J 0
(-1212 4250);
DISPLAY 0.638298 (-1212 4250);
PAINT MONO (-1212 4250);
FORCEPROP 2 LAST CDS_LIB mstr_standard
J 0
(-750 4250);
PAINT ORANGE (-750 4250);
DISPLAY INVISIBLE (-750 4250);
FORCEPROP 2 LAST PATH I35
J 0
(-1025 4300);
DISPLAY 1.021277 (-1025 4300);
PAINT ORANGE (-1025 4300);
DISPLAY INVISIBLE (-1025 4300);
FORCEPROP 1 LAST OFFPAGE TRUE
J 0
(-425 4125);
DISPLAY 0.872340 (-425 4125);
PAINT GREEN (-425 4125);
DISPLAY INVISIBLE (-425 4125);
FORCEPROP 1 LAST COMMENT_BODY TRUE
J 0
(-625 4150);
DISPLAY 0.872340 (-625 4150);
PAINT GREEN (-625 4150);
DISPLAY INVISIBLE (-625 4150);
FORCEADD RES..1
(-2100 2075);
FORCEPROP 1 LAST PACK_TYPE 0402
J 0
(-2000 2025);
DISPLAY 0.617021 (-2000 2025);
PAINT SKYBLUE (-2000 2025);
FORCEPROP 1 LAST PART_NUMBER G21497-005
J 0
(-1950 2075);
DISPLAY 0.617021 (-1950 2075);
PAINT BLUE (-1950 2075);
FORCEPROP 1 LAST LOCATION R7G15
J 0
(-2150 2125);
DISPLAY 0.617021 (-2150 2125);
PAINT AQUA (-2150 2125);
FORCEPROP 1 LASTPIN (-2000 2075) $PN 2
J 0
(-2038 2087);
DISPLAY 0.617021 (-2038 2087);
PAINT ORANGE (-2038 2087);
FORCEPROP 1 LAST MATERIAL EMPTY
J 0
(-2150 2025);
DISPLAY 0.617021 (-2150 2025);
PAINT RED (-2150 2025);
FORCEPROP 1 LASTPIN (-2200 2075) $PN 1
J 0
(-2188 2087);
DISPLAY 0.617021 (-2188 2087);
PAINT ORANGE (-2188 2087);
FORCEPROP 1 LAST TOLERANCE 5%
J 0
(-2250 2075);
DISPLAY 0.617021 (-2250 2075);
PAINT SKYBLUE (-2250 2075);
FORCEPROP 1 LAST WATTAGE 1/16W
J 2
(-2175 2025);
DISPLAY 0.617021 (-2175 2025);
PAINT SKYBLUE (-2175 2025);
FORCEPROP 1 LAST VALUE 0.0
J 2
(-2275 2075);
DISPLAY 0.617021 (-2275 2075);
PAINT SKYBLUE (-2275 2075);
FORCEPROP 2 LAST SEC_TYPE 0402
J 0
(-2150 2275);
DISPLAY 1.021277 (-2150 2275);
PAINT ORANGE (-2150 2275);
DISPLAY INVISIBLE (-2150 2275);
FORCEPROP 2 LAST SEC 1
J 0
(-2150 2275);
PAINT MONO (-2150 2275);
DISPLAY INVISIBLE (-2150 2275);
FORCEPROP 2 LAST BOM_COST DEBUG
J 0
(-2150 2225);
DISPLAY 1.021277 (-2150 2225);
PAINT ORANGE (-2150 2225);
DISPLAY INVISIBLE (-2150 2225);
FORCEPROP 1 LAST PATH I36
J 0
(-2150 2225);
DISPLAY 0.978723 (-2150 2225);
PAINT WHITE (-2150 2225);
DISPLAY INVISIBLE (-2150 2225);
FORCEPROP 2 LAST ROOM BMC_DEBUG_HEADER
J 0
(-2150 2175);
DISPLAY 1.021277 (-2150 2175);
PAINT ORANGE (-2150 2175);
DISPLAY INVISIBLE (-2150 2175);
FORCEPROP 2 LAST CDS_LOCATION R7G15
J 0
(-2150 2125);
DISPLAY 0.617021 (-2150 2125);
PAINT AQUA (-2150 2125);
DISPLAY INVISIBLE (-2150 2125);
FORCEPROP 2 LAST CDS_LIB mstr_discrete
J 0
(-2100 2075);
PAINT MONO (-2100 2075);
DISPLAY INVISIBLE (-2100 2075);
FORCEADD RES..1
(-2100 1900);
FORCEPROP 1 LAST VALUE 0.0
J 2
(-2275 1900);
DISPLAY 0.617021 (-2275 1900);
PAINT SKYBLUE (-2275 1900);
FORCEPROP 1 LAST WATTAGE 1/16W
J 2
(-2175 1850);
DISPLAY 0.617021 (-2175 1850);
PAINT SKYBLUE (-2175 1850);
FORCEPROP 1 LAST TOLERANCE 5%
J 0
(-2250 1900);
DISPLAY 0.617021 (-2250 1900);
PAINT SKYBLUE (-2250 1900);
FORCEPROP 1 LASTPIN (-2200 1900) $PN 1
J 0
(-2188 1912);
DISPLAY 0.617021 (-2188 1912);
PAINT ORANGE (-2188 1912);
FORCEPROP 1 LAST PACK_TYPE 0402
J 0
(-2000 1850);
DISPLAY 0.617021 (-2000 1850);
PAINT SKYBLUE (-2000 1850);
FORCEPROP 1 LAST MATERIAL CHIP
J 0
(-2150 1850);
DISPLAY 0.617021 (-2150 1850);
PAINT SKYBLUE (-2150 1850);
FORCEPROP 1 LASTPIN (-2000 1900) $PN 2
J 0
(-2038 1912);
DISPLAY 0.617021 (-2038 1912);
PAINT ORANGE (-2038 1912);
FORCEPROP 1 LAST LOCATION R7G17
J 0
(-2150 1950);
DISPLAY 0.617021 (-2150 1950);
PAINT AQUA (-2150 1950);
FORCEPROP 1 LAST PART_NUMBER G21497-005
J 0
(-1950 1900);
DISPLAY 0.617021 (-1950 1900);
PAINT BLUE (-1950 1900);
FORCEPROP 1 LAST PATH I37
J 0
(-2150 2050);
DISPLAY 0.978723 (-2150 2050);
PAINT WHITE (-2150 2050);
DISPLAY INVISIBLE (-2150 2050);
FORCEPROP 2 LAST CDS_LOCATION R7G17
J 0
(-2150 1950);
DISPLAY 0.617021 (-2150 1950);
PAINT AQUA (-2150 1950);
DISPLAY INVISIBLE (-2150 1950);
FORCEPROP 2 LAST ROOM BMC_DEBUG_HEADER
J 0
(-2150 2000);
DISPLAY 1.021277 (-2150 2000);
PAINT ORANGE (-2150 2000);
DISPLAY INVISIBLE (-2150 2000);
FORCEPROP 2 LAST SEC 1
J 0
(-2150 2100);
DISPLAY 0.680851 (-2150 2100);
PAINT MONO (-2150 2100);
DISPLAY INVISIBLE (-2150 2100);
FORCEPROP 2 LAST BOM_COST DEBUG
J 0
(-2150 2050);
DISPLAY 1.021277 (-2150 2050);
PAINT ORANGE (-2150 2050);
DISPLAY INVISIBLE (-2150 2050);
FORCEPROP 2 LAST SEC_TYPE 0402
J 0
(-2150 2100);
DISPLAY 1.021277 (-2150 2100);
PAINT ORANGE (-2150 2100);
DISPLAY INVISIBLE (-2150 2100);
FORCEPROP 2 LAST CDS_LIB mstr_discrete
J 0
(-2100 1900);
PAINT ORANGE (-2100 1900);
DISPLAY INVISIBLE (-2100 1900);
FORCEADD RES..1
(-125 4050);
FORCEPROP 1 LASTPIN (-25 4050) $PN 2
J 0
(-63 4062);
DISPLAY 0.617021 (-63 4062);
PAINT ORANGE (-63 4062);
FORCEPROP 1 LAST WATTAGE 1/16W
J 2
(-175 4000);
DISPLAY 0.617021 (-175 4000);
PAINT SKYBLUE (-175 4000);
FORCEPROP 1 LAST MATERIAL CHIP
J 0
(-150 4000);
DISPLAY 0.617021 (-150 4000);
PAINT SKYBLUE (-150 4000);
FORCEPROP 1 LAST PACK_TYPE 0402
J 0
(-50 4000);
DISPLAY 0.617021 (-50 4000);
PAINT SKYBLUE (-50 4000);
FORCEPROP 1 LAST LOCATION R7G14
J 0
(-175 4100);
DISPLAY 0.617021 (-175 4100);
PAINT AQUA (-175 4100);
FORCEPROP 1 LASTPIN (-225 4050) $PN 1
J 0
(-213 4062);
DISPLAY 0.617021 (-213 4062);
PAINT ORANGE (-213 4062);
FORCEPROP 1 LAST PART_NUMBER G21497-005
J 0
(-250 4125);
DISPLAY 0.617021 (-250 4125);
PAINT BLUE (-250 4125);
FORCEPROP 1 LAST VALUE 0.0
J 2
(-175 3975);
DISPLAY 0.617021 (-175 3975);
PAINT SKYBLUE (-175 3975);
FORCEPROP 1 LAST TOLERANCE 5%
J 0
(-150 3975);
DISPLAY 0.617021 (-150 3975);
PAINT SKYBLUE (-150 3975);
FORCEPROP 2 LAST CDS_LOCATION R7G14
J 0
(-175 4100);
DISPLAY 0.617021 (-175 4100);
PAINT AQUA (-175 4100);
DISPLAY INVISIBLE (-175 4100);
FORCEPROP 2 LAST ROOM BMC_DEBUG_HEADER
J 0
(-175 4150);
DISPLAY 1.021277 (-175 4150);
PAINT ORANGE (-175 4150);
DISPLAY INVISIBLE (-175 4150);
FORCEPROP 2 LAST CDS_LIB mstr_discrete
J 0
(-125 4050);
PAINT ORANGE (-125 4050);
DISPLAY INVISIBLE (-125 4050);
FORCEPROP 1 LAST PATH I38
J 0
(-175 4200);
DISPLAY 0.978723 (-175 4200);
PAINT WHITE (-175 4200);
DISPLAY INVISIBLE (-175 4200);
FORCEPROP 2 LAST BOM_COST DEBUG
J 0
(-175 4200);
DISPLAY 1.021277 (-175 4200);
PAINT ORANGE (-175 4200);
DISPLAY INVISIBLE (-175 4200);
FORCEPROP 2 LAST SEC 1
J 0
(-175 4250);
DISPLAY 0.680851 (-175 4250);
PAINT MONO (-175 4250);
DISPLAY INVISIBLE (-175 4250);
FORCEPROP 2 LAST SEC_TYPE 0402
J 0
(-175 4250);
DISPLAY 1.021277 (-175 4250);
PAINT ORANGE (-175 4250);
DISPLAY INVISIBLE (-175 4250);
FORCEADD OFFPAGE..5
(-2850 2075);
FORCEPROP 2 LAST $XR0 120 
J 0
(-3105 2075);
DISPLAY 0.638298 (-3105 2075);
PAINT MONO (-3105 2075);
FORCEPROP 2 LAST PATH I39
J 0
(-3125 2125);
DISPLAY 1.021277 (-3125 2125);
PAINT ORANGE (-3125 2125);
DISPLAY INVISIBLE (-3125 2125);
FORCEPROP 2 LAST CDS_LIB mstr_standard
J 0
(-2850 2075);
PAINT MONO (-2850 2075);
DISPLAY INVISIBLE (-2850 2075);
FORCEPROP 1 LAST OFFPAGE TRUE
J 0
(-2525 1950);
DISPLAY 0.872340 (-2525 1950);
PAINT GREEN (-2525 1950);
DISPLAY INVISIBLE (-2525 1950);
FORCEPROP 1 LAST COMMENT_BODY TRUE
J 0
(-2750 2000);
DISPLAY 0.872340 (-2750 2000);
PAINT GREEN (-2750 2000);
DISPLAY INVISIBLE (-2750 2000);
FORCEADD OFFPAGE..1
(-2850 3500);
FORCEPROP 2 LAST $XR0 120 
J 0
(-3102 3500);
DISPLAY 0.638298 (-3102 3500);
PAINT MONO (-3102 3500);
FORCEPROP 2 LAST CDS_LIB mstr_standard
J 0
(-2850 3500);
PAINT MONO (-2850 3500);
DISPLAY INVISIBLE (-2850 3500);
FORCEPROP 2 LAST PATH I4
J 0
(-3125 3550);
DISPLAY 1.021277 (-3125 3550);
PAINT ORANGE (-3125 3550);
DISPLAY INVISIBLE (-3125 3550);
FORCEPROP 1 LAST OFFPAGE TRUE
J 0
(-2525 3375);
DISPLAY 0.872340 (-2525 3375);
PAINT GREEN (-2525 3375);
DISPLAY INVISIBLE (-2525 3375);
FORCEPROP 1 LAST COMMENT_BODY TRUE
J 0
(-2725 3400);
DISPLAY 0.872340 (-2725 3400);
PAINT GREEN (-2725 3400);
DISPLAY INVISIBLE (-2725 3400);
FORCEADD OFFPAGE..5
(-750 4050);
FORCEPROP 2 LAST $XR0 245 
J 0
(-1095 4050);
DISPLAY 0.638298 (-1095 4050);
PAINT MONO (-1095 4050);
FORCEPROP 2 LAST CDS_LIB mstr_standard
J 0
(-750 4050);
PAINT ORANGE (-750 4050);
DISPLAY INVISIBLE (-750 4050);
FORCEPROP 2 LAST PATH I40
J 0
(-1025 4100);
DISPLAY 1.021277 (-1025 4100);
PAINT ORANGE (-1025 4100);
DISPLAY INVISIBLE (-1025 4100);
FORCEPROP 1 LAST OFFPAGE TRUE
J 0
(-425 3925);
DISPLAY 0.872340 (-425 3925);
PAINT GREEN (-425 3925);
DISPLAY INVISIBLE (-425 3925);
FORCEPROP 1 LAST COMMENT_BODY TRUE
J 0
(-650 3975);
DISPLAY 0.872340 (-650 3975);
PAINT GREEN (-650 3975);
DISPLAY INVISIBLE (-650 3975);
FORCEADD OFFPAGE..5
(-2850 1900);
FORCEPROP 2 LAST $XR1 255 
J 0
(-3225 1900);
DISPLAY 0.638298 (-3225 1900);
PAINT MONO (-3225 1900);
FORCEPROP 2 LAST $XR0 144 
J 0
(-3105 1900);
DISPLAY 0.638298 (-3105 1900);
PAINT MONO (-3105 1900);
FORCEPROP 2 LAST CDS_LIB mstr_standard
J 0
(-2850 1900);
PAINT ORANGE (-2850 1900);
DISPLAY INVISIBLE (-2850 1900);
FORCEPROP 2 LAST PATH I41
J 0
(-3125 1950);
DISPLAY 1.021277 (-3125 1950);
PAINT ORANGE (-3125 1950);
DISPLAY INVISIBLE (-3125 1950);
FORCEPROP 1 LAST OFFPAGE TRUE
J 0
(-2525 1775);
DISPLAY 0.872340 (-2525 1775);
PAINT GREEN (-2525 1775);
DISPLAY INVISIBLE (-2525 1775);
FORCEPROP 1 LAST COMMENT_BODY TRUE
J 0
(-2750 1825);
DISPLAY 0.872340 (-2750 1825);
PAINT GREEN (-2750 1825);
DISPLAY INVISIBLE (-2750 1825);
FORCEADD OFFPAGE..2
(1000 1800);
FORCEPROP 2 LASTPIN (950 1800) SIG_NAME FM_JTAG_PLD_EN_DEBUG
J 2
(940 1810);
DISPLAY 0.617021 (940 1810);
PAINT ORANGE (940 1810);
FORCEPROP 2 LAST $XR0 191 
J 0
(1189 1800);
DISPLAY 0.638298 (1189 1800);
PAINT MONO (1189 1800);
FORCEPROP 1 LAST COMMENT_BODY TRUE
J 0
(955 1705);
DISPLAY 0.872340 (955 1705);
PAINT GREEN (955 1705);
DISPLAY INVISIBLE (955 1705);
FORCEPROP 1 LAST OFFPAGE TRUE
J 0
(1325 1675);
DISPLAY 0.872340 (1325 1675);
PAINT GREEN (1325 1675);
DISPLAY INVISIBLE (1325 1675);
FORCEPROP 2 LAST PATH I42
J 0
(1200 1850);
DISPLAY 1.021277 (1200 1850);
PAINT ORANGE (1200 1850);
DISPLAY INVISIBLE (1200 1850);
FORCEPROP 2 LAST CDS_LIB mstr_standard
J 0
(1000 1800);
PAINT MONO (1000 1800);
DISPLAY INVISIBLE (1000 1800);
FORCEADD P3V3_STBY..1
(175 2200);
FORCEPROP 3 LASTPIN (175 2150) SIG_NAME P3V3_STBY\g
J 0
(185 2160);
DISPLAY 0.659574 (185 2160);
PAINT MONO (185 2160);
DISPLAY INVISIBLE (185 2160);
FORCEPROP 1 LAST HDL_POWER P3V3_STBY
J 0
(-125 2075);
DISPLAY 0.872340 (-125 2075);
PAINT ORANGE (-125 2075);
DISPLAY INVISIBLE (-125 2075);
FORCEPROP 1 LAST BODY_TYPE PLUMBING
J 0
(130 2157);
DISPLAY 0.340426 (130 2157);
PAINT GREEN (130 2157);
DISPLAY INVISIBLE (130 2157);
FORCEPROP 1 LAST SIZE 1B
J 0
(220 2222);
DISPLAY 0.340426 (220 2222);
PAINT GREEN (220 2222);
DISPLAY INVISIBLE (220 2222);
FORCEPROP 2 LAST CDS_LIB mstr_symbols
J 0
(175 2200);
PAINT MONO (175 2200);
DISPLAY INVISIBLE (175 2200);
FORCEPROP 1 LAST VOLTAGE 3.3V
J 0
(130 2157);
DISPLAY 0.340426 (130 2157);
PAINT SKYBLUE (130 2157);
DISPLAY INVISIBLE (130 2157);
FORCEPROP 1 LAST PATH I43
J 0
(220 2202);
DISPLAY 0.340426 (220 2202);
PAINT GREEN (220 2202);
DISPLAY INVISIBLE (220 2202);
FORCEADD RES..2
(175 2000);
FORCEPROP 1 LAST LOCATION R3R15
J 0
(220 2125);
DISPLAY 0.617021 (220 2125);
PAINT AQUA (220 2125);
FORCEPROP 1 LAST TOLERANCE 1%
J 0
(220 2025);
DISPLAY 0.617021 (220 2025);
PAINT SKYBLUE (220 2025);
FORCEPROP 1 LASTPIN (175 2100) $PN 1
J 0
(180 2062);
DISPLAY 0.617021 (180 2062);
PAINT ORANGE (180 2062);
FORCEPROP 1 LASTPIN (175 1900) $PN 2
J 0
(180 1910);
DISPLAY 0.617021 (180 1910);
PAINT ORANGE (180 1910);
FORCEPROP 1 LAST PACK_TYPE 0402
J 0
(215 1825);
DISPLAY 0.617021 (215 1825);
PAINT SKYBLUE (215 1825);
FORCEPROP 1 LAST PART_NUMBER G21796-026
J 0
(215 1875);
DISPLAY 0.617021 (215 1875);
PAINT BLUE (215 1875);
FORCEPROP 1 LAST VALUE 1.00K
J 0
(220 2075);
DISPLAY 0.617021 (220 2075);
PAINT SKYBLUE (220 2075);
FORCEPROP 1 LAST MATERIAL CHIP
J 0
(215 1925);
DISPLAY 0.617021 (215 1925);
PAINT SKYBLUE (215 1925);
FORCEPROP 1 LAST WATTAGE 1/16W
J 0
(215 1975);
DISPLAY 0.617021 (215 1975);
PAINT SKYBLUE (215 1975);
FORCEPROP 2 LAST SEC_TYPE 0402
J 0
(225 2225);
DISPLAY 1.021277 (225 2225);
PAINT ORANGE (225 2225);
DISPLAY INVISIBLE (225 2225);
FORCEPROP 2 LAST SEC 1
J 0
(225 2225);
DISPLAY 0.680851 (225 2225);
PAINT MONO (225 2225);
DISPLAY INVISIBLE (225 2225);
FORCEPROP 2 LAST CDS_LOCATION R3R15
J 0
(220 2125);
DISPLAY 0.617021 (220 2125);
PAINT AQUA (220 2125);
DISPLAY INVISIBLE (220 2125);
FORCEPROP 1 LAST PATH I44
J 0
(225 2175);
DISPLAY 0.978723 (225 2175);
PAINT WHITE (225 2175);
DISPLAY INVISIBLE (225 2175);
FORCEPROP 0 LAST ROOM BMC_DEBUG_HEADER
J 0
(225 2225);
DISPLAY 1.021277 (225 2225);
PAINT ORANGE (225 2225);
DISPLAY INVISIBLE (225 2225);
FORCEPROP 2 LAST CDS_LIB mstr_discrete
J 0
(175 2000);
PAINT ORANGE (175 2000);
DISPLAY INVISIBLE (175 2000);
FORCEADD RES..2
(175 1600);
FORCEPROP 1 LAST LOCATION R3R11
J 0
(220 1725);
DISPLAY 0.617021 (220 1725);
PAINT AQUA (220 1725);
FORCEPROP 1 LAST VALUE 10.0K
J 0
(220 1675);
DISPLAY 0.617021 (220 1675);
PAINT SKYBLUE (220 1675);
FORCEPROP 1 LAST TOLERANCE 1%
J 0
(220 1625);
DISPLAY 0.617021 (220 1625);
PAINT SKYBLUE (220 1625);
FORCEPROP 1 LASTPIN (175 1700) $PN 1
J 0
(180 1662);
DISPLAY 0.617021 (180 1662);
PAINT ORANGE (180 1662);
FORCEPROP 1 LASTPIN (175 1500) $PN 2
J 0
(180 1510);
DISPLAY 0.617021 (180 1510);
PAINT ORANGE (180 1510);
FORCEPROP 1 LAST PACK_TYPE 0402
J 0
(215 1425);
DISPLAY 0.617021 (215 1425);
PAINT SKYBLUE (215 1425);
FORCEPROP 1 LAST MATERIAL EMPTY
J 0
(215 1525);
DISPLAY 0.617021 (215 1525);
PAINT RED (215 1525);
FORCEPROP 1 LAST WATTAGE 1/16W
J 0
(215 1575);
DISPLAY 0.617021 (215 1575);
PAINT SKYBLUE (215 1575);
FORCEPROP 1 LAST PART_NUMBER G21796-016
J 0
(215 1475);
DISPLAY 0.617021 (215 1475);
PAINT BLUE (215 1475);
FORCEPROP 2 LAST CDS_LIB mstr_discrete
J 0
(175 1600);
PAINT ORANGE (175 1600);
DISPLAY INVISIBLE (175 1600);
FORCEPROP 2 LAST CDS_LOCATION R3R11
J 0
(220 1725);
DISPLAY 0.617021 (220 1725);
PAINT AQUA (220 1725);
DISPLAY INVISIBLE (220 1725);
FORCEPROP 1 LAST PATH I45
J 0
(225 1775);
DISPLAY 0.978723 (225 1775);
PAINT WHITE (225 1775);
DISPLAY INVISIBLE (225 1775);
FORCEPROP 2 LAST SEC 1
J 0
(225 1825);
DISPLAY 0.680851 (225 1825);
PAINT MONO (225 1825);
DISPLAY INVISIBLE (225 1825);
FORCEPROP 0 LAST ROOM BMC_DEBUG_HEADER
J 0
(225 1825);
DISPLAY 1.021277 (225 1825);
PAINT ORANGE (225 1825);
DISPLAY INVISIBLE (225 1825);
FORCEPROP 2 LAST SEC_TYPE 0402
J 0
(225 1825);
DISPLAY 1.021277 (225 1825);
PAINT ORANGE (225 1825);
DISPLAY INVISIBLE (225 1825);
FORCEADD GND..1
(175 1400);
FORCEPROP 3 LASTPIN (175 1450) SIG_NAME GND\g
J 0
(185 1460);
DISPLAY 0.659574 (185 1460);
PAINT MONO (185 1460);
DISPLAY INVISIBLE (185 1460);
FORCEPROP 1 LAST SIZE 1B
J 0
(250 1350);
DISPLAY 0.872340 (250 1350);
PAINT AQUA (250 1350);
DISPLAY INVISIBLE (250 1350);
FORCEPROP 2 LAST CDS_LIB mstr_symbols
J 0
(175 1400);
PAINT MONO (175 1400);
DISPLAY INVISIBLE (175 1400);
FORCEPROP 1 LAST VOLTAGE 0.0V
J 0
(130 1357);
DISPLAY 0.340426 (130 1357);
PAINT SKYBLUE (130 1357);
DISPLAY INVISIBLE (130 1357);
FORCEPROP 1 LAST PATH I46
J 0
(250 1400);
DISPLAY 0.872340 (250 1400);
PAINT AQUA (250 1400);
DISPLAY INVISIBLE (250 1400);
FORCEPROP 1 LAST BODY_TYPE PLUMBING
J 0
(130 1357);
DISPLAY 0.340426 (130 1357);
PAINT GREEN (130 1357);
DISPLAY INVISIBLE (130 1357);
FORCEPROP 1 LAST HDL_POWER GND
J 0
(175 1550);
DISPLAY 0.872340 (175 1550);
PAINT GREEN (175 1550);
DISPLAY INVISIBLE (175 1550);
FORCEADD CONN8_C77962004..1
R 2
(4000 3125);
FORCEPROP 2 LASTPIN (3800 2925) $PN 8
J 2
(3790 2935);
DISPLAY 0.617021 (3790 2935);
PAINT ORANGE (3790 2935);
FORCEPROP 2 LASTPIN (3800 2975) $PN 7
J 2
(3790 2985);
DISPLAY 0.617021 (3790 2985);
PAINT ORANGE (3790 2985);
FORCEPROP 2 LASTPIN (3800 3025) $PN 6
J 2
(3790 3035);
DISPLAY 0.617021 (3790 3035);
PAINT ORANGE (3790 3035);
FORCEPROP 2 LASTPIN (3800 3075) $PN 5
J 2
(3790 3085);
DISPLAY 0.617021 (3790 3085);
PAINT ORANGE (3790 3085);
FORCEPROP 2 LASTPIN (3800 3125) $PN 4
J 2
(3790 3135);
DISPLAY 0.617021 (3790 3135);
PAINT ORANGE (3790 3135);
FORCEPROP 2 LASTPIN (3800 3175) $PN 3
J 2
(3790 3185);
DISPLAY 0.617021 (3790 3185);
PAINT ORANGE (3790 3185);
FORCEPROP 2 LASTPIN (3800 3225) $PN 2
J 2
(3790 3235);
DISPLAY 0.617021 (3790 3235);
PAINT ORANGE (3790 3235);
FORCEPROP 2 LASTPIN (3800 3275) $PN 1
J 2
(3790 3285);
DISPLAY 0.617021 (3790 3285);
PAINT ORANGE (3790 3285);
FORCEPROP 1 LAST MATERIAL CONN
J 2
(4150 3475);
DISPLAY 0.617021 (4150 3475);
PAINT SKYBLUE (4150 3475);
FORCEPROP 1 LAST PART_NUMBER C77962-004
J 2
(4150 2775);
DISPLAY 0.617021 (4150 2775);
PAINT BLUE (4150 2775);
FORCEPROP 1 LAST LOCATION J7G2
J 2
(4100 3550);
DISPLAY 0.617021 (4100 3550);
PAINT AQUA (4100 3550);
FORCEPROP 1 LAST PATH I47
J 2
(3700 3475);
PAINT GREEN (3700 3475);
DISPLAY INVISIBLE (3700 3475);
FORCEPROP 2 LAST CDS_LOCATION J7G2
J 2
(4100 3550);
DISPLAY 0.617021 (4100 3550);
PAINT AQUA (4100 3550);
DISPLAY INVISIBLE (4100 3550);
FORCEPROP 2 LAST CDS_LIB mstr_conn
J 0
(4000 3125);
PAINT ORANGE (4000 3125);
DISPLAY INVISIBLE (4000 3125);
FORCEPROP 1 LAST PACK_TYPE PIP
J 2
(4150 3575);
PAINT SKYBLUE (4150 3575);
DISPLAY INVISIBLE (4150 3575);
FORCEPROP 0 LAST ROOM BMC_DEBUG_HEADER
J 2
(4150 3600);
DISPLAY 1.021277 (4150 3600);
PAINT ORANGE (4150 3600);
DISPLAY INVISIBLE (4150 3600);
FORCEPROP 2 LAST SEC 1
J 0
(4100 3600);
DISPLAY 0.680851 (4100 3600);
PAINT MONO (4100 3600);
DISPLAY INVISIBLE (4100 3600);
FORCEPROP 2 LAST SEC_TYPE PIP
J 0
(4100 3600);
DISPLAY 1.021277 (4100 3600);
PAINT ORANGE (4100 3600);
DISPLAY INVISIBLE (4100 3600);
FORCEPROP 0 LAST BOM_COST DEBUG
J 2
(4150 3600);
DISPLAY 1.021277 (4150 3600);
PAINT ORANGE (4150 3600);
DISPLAY INVISIBLE (4150 3600);
FORCEADD P3V3_STBY..1
(3375 3850);
FORCEPROP 3 LASTPIN (3375 3800) SIG_NAME P3V3_STBY\g
J 0
(3385 3810);
DISPLAY 0.659574 (3385 3810);
PAINT MONO (3385 3810);
DISPLAY INVISIBLE (3385 3810);
FORCEPROP 1 LAST SIZE 1B
J 0
(3420 3872);
DISPLAY 0.340426 (3420 3872);
PAINT GREEN (3420 3872);
DISPLAY INVISIBLE (3420 3872);
FORCEPROP 2 LAST CDS_LIB mstr_symbols
J 0
(3375 3850);
PAINT MONO (3375 3850);
DISPLAY INVISIBLE (3375 3850);
FORCEPROP 1 LAST PATH I48
J 0
(3420 3852);
DISPLAY 0.340426 (3420 3852);
PAINT GREEN (3420 3852);
DISPLAY INVISIBLE (3420 3852);
FORCEPROP 1 LAST VOLTAGE 3.3V
J 0
(3330 3807);
DISPLAY 0.340426 (3330 3807);
PAINT SKYBLUE (3330 3807);
DISPLAY INVISIBLE (3330 3807);
FORCEPROP 1 LAST BODY_TYPE PLUMBING
J 0
(3330 3807);
DISPLAY 0.340426 (3330 3807);
PAINT GREEN (3330 3807);
DISPLAY INVISIBLE (3330 3807);
FORCEPROP 1 LAST HDL_POWER P3V3_STBY
J 0
(3075 3725);
DISPLAY 0.872340 (3075 3725);
PAINT ORANGE (3075 3725);
DISPLAY INVISIBLE (3075 3725);
FORCEADD DIODE..1
(3500 3525);
FORCEPROP 1 LAST PACK_TYPE SMLF
J 0
(3475 3285);
DISPLAY 0.617021 (3475 3285);
PAINT SKYBLUE (3475 3285);
FORCEPROP 1 LAST VALUE 1N5819HW
J 0
(3475 3400);
DISPLAY 0.617021 (3475 3400);
PAINT SKYBLUE (3475 3400);
FORCEPROP 1 LAST PART_NUMBER D55839-001
J 0
(3475 3625);
DISPLAY 0.617021 (3475 3625);
PAINT BLUE (3475 3625);
FORCEPROP 1 LAST MATERIAL IC
J 0
(3475 3347);
DISPLAY 0.617021 (3475 3347);
PAINT SKYBLUE (3475 3347);
FORCEPROP 1 LAST LOCATION CR3U1
J 0
(3473 3681);
DISPLAY 0.617021 (3473 3681);
PAINT AQUA (3473 3681);
FORCEPROP 1 LASTPIN (3600 3525) $PN 1
J 0
(3565 3535);
DISPLAY 0.617021 (3565 3535);
PAINT AQUA (3565 3535);
FORCEPROP 1 LASTPIN (3400 3525) $PN 2
J 2
(3435 3535);
DISPLAY 0.617021 (3435 3535);
PAINT AQUA (3435 3535);
FORCEPROP 0 LAST BOM_COST DEBUG
J 0
(3475 3875);
DISPLAY 1.021277 (3475 3875);
PAINT ORANGE (3475 3875);
DISPLAY INVISIBLE (3475 3875);
FORCEPROP 2 LAST SEC 1
J 0
(3500 3800);
DISPLAY 0.680851 (3500 3800);
PAINT MONO (3500 3800);
DISPLAY INVISIBLE (3500 3800);
FORCEPROP 2 LAST SEC_TYPE SMLF
J 0
(3500 3800);
DISPLAY 1.021277 (3500 3800);
PAINT ORANGE (3500 3800);
DISPLAY INVISIBLE (3500 3800);
FORCEPROP 0 LAST ROOM BMC_DEBUG_HEADER
J 0
(3475 3775);
DISPLAY 1.021277 (3475 3775);
PAINT ORANGE (3475 3775);
DISPLAY INVISIBLE (3475 3775);
FORCEPROP 1 LAST PATH I49
J 0
(3480 3735);
DISPLAY 0.978723 (3480 3735);
PAINT PINK (3480 3735);
DISPLAY INVISIBLE (3480 3735);
FORCEPROP 2 LAST CDS_LIB mstr_discrete
J 0
(3500 3525);
PAINT MONO (3500 3525);
DISPLAY INVISIBLE (3500 3525);
FORCEADD OFFPAGE..2
(-1375 4775);
FORCEPROP 2 LAST $XR0 189 
J 0
(-1096 4775);
DISPLAY 0.638298 (-1096 4775);
PAINT MONO (-1096 4775);
FORCEPROP 2 LAST PATH I5
J 0
(-1175 4825);
DISPLAY 1.021277 (-1175 4825);
PAINT ORANGE (-1175 4825);
DISPLAY INVISIBLE (-1175 4825);
FORCEPROP 2 LAST CDS_LIB mstr_standard
J 0
(-1375 4775);
PAINT ORANGE (-1375 4775);
DISPLAY INVISIBLE (-1375 4775);
FORCEPROP 1 LAST OFFPAGE TRUE
J 0
(-1050 4650);
DISPLAY 0.872340 (-1050 4650);
PAINT GREEN (-1050 4650);
DISPLAY INVISIBLE (-1050 4650);
FORCEPROP 1 LAST COMMENT_BODY TRUE
J 0
(-1420 4680);
DISPLAY 0.872340 (-1420 4680);
PAINT GREEN (-1420 4680);
DISPLAY INVISIBLE (-1420 4680);
FORCEADD RES..2
(3200 3500);
FORCEPROP 1 LAST PART_NUMBER G21796-016
J 0
(3240 3375);
DISPLAY 0.617021 (3240 3375);
PAINT BLUE (3240 3375);
FORCEPROP 1 LAST MATERIAL CHIP
J 0
(3240 3425);
DISPLAY 0.617021 (3240 3425);
PAINT SKYBLUE (3240 3425);
FORCEPROP 1 LAST WATTAGE 1/16W
J 0
(3240 3475);
DISPLAY 0.617021 (3240 3475);
PAINT SKYBLUE (3240 3475);
FORCEPROP 1 LAST VALUE 10.0K
J 0
(3245 3575);
DISPLAY 0.617021 (3245 3575);
PAINT SKYBLUE (3245 3575);
FORCEPROP 1 LAST LOCATION R8G20
J 0
(3245 3625);
DISPLAY 0.617021 (3245 3625);
PAINT AQUA (3245 3625);
FORCEPROP 1 LAST TOLERANCE 1%
J 0
(3245 3525);
DISPLAY 0.617021 (3245 3525);
PAINT SKYBLUE (3245 3525);
FORCEPROP 1 LAST PACK_TYPE 0402
J 0
(3240 3325);
DISPLAY 0.617021 (3240 3325);
PAINT SKYBLUE (3240 3325);
FORCEPROP 2 LAST CDS_SEC 1
J 0
(3250 3725);
PAINT MONO (3250 3725);
DISPLAY INVISIBLE (3250 3725);
FORCEPROP 2 LAST $SEC 1
J 0
(3250 3725);
PAINT MONO (3250 3725);
DISPLAY INVISIBLE (3250 3725);
FORCEPROP 2 LAST CDS_LOCATION R8G20
J 0
(3245 3625);
DISPLAY 0.617021 (3245 3625);
PAINT AQUA (3245 3625);
DISPLAY INVISIBLE (3245 3625);
FORCEPROP 1 LAST PATH I50
J 0
(3250 3675);
DISPLAY 0.978723 (3250 3675);
PAINT WHITE (3250 3675);
DISPLAY INVISIBLE (3250 3675);
FORCEPROP 2 LAST ROOM BMC_DEBUG_HEADER
J 0
(3150 3600);
DISPLAY 1.021277 (3150 3600);
PAINT ORANGE (3150 3600);
DISPLAY INVISIBLE (3150 3600);
FORCEPROP 1 LASTPIN (3200 3600) $PN 1
J 0
(3205 3562);
DISPLAY 0.787234 (3205 3562);
PAINT ORANGE (3205 3562);
DISPLAY INVISIBLE (3205 3562);
FORCEPROP 2 LAST CDS_LIB mstr_discrete
J 0
(3200 3500);
PAINT ORANGE (3200 3500);
DISPLAY INVISIBLE (3200 3500);
FORCEPROP 1 LASTPIN (3200 3400) $PN 2
J 0
(3205 3410);
DISPLAY 0.787234 (3205 3410);
PAINT ORANGE (3205 3410);
DISPLAY INVISIBLE (3205 3410);
FORCEADD RES..2
(2900 3500);
FORCEPROP 1 LAST MATERIAL CHIP
J 0
(2940 3425);
DISPLAY 0.617021 (2940 3425);
PAINT SKYBLUE (2940 3425);
FORCEPROP 1 LAST PART_NUMBER G21796-016
J 0
(2940 3375);
DISPLAY 0.617021 (2940 3375);
PAINT BLUE (2940 3375);
FORCEPROP 1 LAST VALUE 10.0K
J 0
(2945 3575);
DISPLAY 0.617021 (2945 3575);
PAINT SKYBLUE (2945 3575);
FORCEPROP 1 LAST PACK_TYPE 0402
J 0
(2940 3325);
DISPLAY 0.617021 (2940 3325);
PAINT SKYBLUE (2940 3325);
FORCEPROP 1 LAST LOCATION R7G23
J 0
(2945 3625);
DISPLAY 0.617021 (2945 3625);
PAINT AQUA (2945 3625);
FORCEPROP 1 LAST TOLERANCE 1%
J 0
(2945 3525);
DISPLAY 0.617021 (2945 3525);
PAINT SKYBLUE (2945 3525);
FORCEPROP 1 LAST WATTAGE 1/16W
J 0
(2940 3475);
DISPLAY 0.617021 (2940 3475);
PAINT SKYBLUE (2940 3475);
FORCEPROP 2 LAST $SEC 1
J 0
(2950 3725);
PAINT MONO (2950 3725);
DISPLAY INVISIBLE (2950 3725);
FORCEPROP 2 LAST CDS_LOCATION R7G23
J 0
(2945 3625);
DISPLAY 0.617021 (2945 3625);
PAINT AQUA (2945 3625);
DISPLAY INVISIBLE (2945 3625);
FORCEPROP 2 LAST CDS_SEC 1
J 0
(2950 3725);
PAINT MONO (2950 3725);
DISPLAY INVISIBLE (2950 3725);
FORCEPROP 1 LAST PATH I51
J 0
(2950 3675);
DISPLAY 0.978723 (2950 3675);
PAINT WHITE (2950 3675);
DISPLAY INVISIBLE (2950 3675);
FORCEPROP 2 LAST ROOM BMC_DEBUG_HEADER
J 0
(2850 3600);
DISPLAY 1.021277 (2850 3600);
PAINT ORANGE (2850 3600);
DISPLAY INVISIBLE (2850 3600);
FORCEPROP 1 LASTPIN (2900 3600) $PN 1
J 0
(2905 3562);
DISPLAY 0.787234 (2905 3562);
PAINT ORANGE (2905 3562);
DISPLAY INVISIBLE (2905 3562);
FORCEPROP 2 LAST CDS_LIB mstr_discrete
J 0
(2900 3500);
PAINT ORANGE (2900 3500);
DISPLAY INVISIBLE (2900 3500);
FORCEPROP 1 LASTPIN (2900 3400) $PN 2
J 0
(2905 3410);
DISPLAY 0.787234 (2905 3410);
PAINT ORANGE (2905 3410);
DISPLAY INVISIBLE (2905 3410);
FORCEADD P3V3_STBY..1
(2600 3875);
FORCEPROP 3 LASTPIN (2600 3825) SIG_NAME P3V3_STBY\g
J 0
(2610 3835);
DISPLAY 0.659574 (2610 3835);
PAINT MONO (2610 3835);
DISPLAY INVISIBLE (2610 3835);
FORCEPROP 1 LAST PATH I52
J 0
(2645 3877);
DISPLAY 0.340426 (2645 3877);
PAINT GREEN (2645 3877);
DISPLAY INVISIBLE (2645 3877);
FORCEPROP 1 LAST SIZE 1B
J 0
(2645 3897);
DISPLAY 0.340426 (2645 3897);
PAINT GREEN (2645 3897);
DISPLAY INVISIBLE (2645 3897);
FORCEPROP 2 LAST CDS_LIB mstr_symbols
J 0
(2600 3875);
PAINT ORANGE (2600 3875);
DISPLAY INVISIBLE (2600 3875);
FORCEPROP 1 LAST VOLTAGE 3.3V
J 0
(2555 3832);
DISPLAY 0.340426 (2555 3832);
PAINT SKYBLUE (2555 3832);
DISPLAY INVISIBLE (2555 3832);
FORCEPROP 1 LAST BODY_TYPE PLUMBING
J 0
(2555 3832);
DISPLAY 0.340426 (2555 3832);
PAINT GREEN (2555 3832);
DISPLAY INVISIBLE (2555 3832);
FORCEPROP 1 LAST HDL_POWER P3V3_STBY
J 0
(2300 3750);
DISPLAY 0.872340 (2300 3750);
PAINT ORANGE (2300 3750);
DISPLAY INVISIBLE (2300 3750);
FORCEADD RES..2
(2600 3500);
FORCEPROP 1 LAST TOLERANCE 1%
J 0
(2645 3525);
DISPLAY 0.617021 (2645 3525);
PAINT SKYBLUE (2645 3525);
FORCEPROP 1 LAST LOCATION R7G22
J 0
(2645 3625);
DISPLAY 0.617021 (2645 3625);
PAINT AQUA (2645 3625);
FORCEPROP 1 LAST WATTAGE 1/16W
J 0
(2640 3475);
DISPLAY 0.617021 (2640 3475);
PAINT SKYBLUE (2640 3475);
FORCEPROP 1 LAST MATERIAL CHIP
J 0
(2640 3425);
DISPLAY 0.617021 (2640 3425);
PAINT SKYBLUE (2640 3425);
FORCEPROP 1 LAST PART_NUMBER G21796-016
J 0
(2640 3375);
DISPLAY 0.617021 (2640 3375);
PAINT BLUE (2640 3375);
FORCEPROP 1 LAST PACK_TYPE 0402
J 0
(2640 3325);
DISPLAY 0.617021 (2640 3325);
PAINT SKYBLUE (2640 3325);
FORCEPROP 1 LAST VALUE 10.0K
J 0
(2645 3575);
DISPLAY 0.617021 (2645 3575);
PAINT SKYBLUE (2645 3575);
FORCEPROP 1 LASTPIN (2600 3600) $PN 1
J 0
(2605 3562);
DISPLAY 0.787234 (2605 3562);
PAINT ORANGE (2605 3562);
DISPLAY INVISIBLE (2605 3562);
FORCEPROP 1 LASTPIN (2600 3400) $PN 2
J 0
(2605 3410);
DISPLAY 0.787234 (2605 3410);
PAINT ORANGE (2605 3410);
DISPLAY INVISIBLE (2605 3410);
FORCEPROP 2 LAST CDS_LIB mstr_discrete
J 0
(2600 3500);
PAINT ORANGE (2600 3500);
DISPLAY INVISIBLE (2600 3500);
FORCEPROP 2 LAST ROOM BMC_DEBUG_HEADER
J 0
(2550 3600);
DISPLAY 1.021277 (2550 3600);
PAINT ORANGE (2550 3600);
DISPLAY INVISIBLE (2550 3600);
FORCEPROP 2 LAST CDS_LOCATION R7G22
J 0
(2645 3625);
DISPLAY 0.617021 (2645 3625);
PAINT AQUA (2645 3625);
DISPLAY INVISIBLE (2645 3625);
FORCEPROP 1 LAST PATH I53
J 0
(2650 3675);
DISPLAY 0.978723 (2650 3675);
PAINT WHITE (2650 3675);
DISPLAY INVISIBLE (2650 3675);
FORCEPROP 2 LAST CDS_SEC 1
J 0
(2650 3725);
PAINT MONO (2650 3725);
DISPLAY INVISIBLE (2650 3725);
FORCEPROP 2 LAST $SEC 1
J 0
(2650 3725);
PAINT MONO (2650 3725);
DISPLAY INVISIBLE (2650 3725);
FORCEADD GND..1
(3675 2800);
FORCEPROP 3 LASTPIN (3675 2850) SIG_NAME GND\g
J 0
(3685 2860);
DISPLAY 0.659574 (3685 2860);
PAINT MONO (3685 2860);
DISPLAY INVISIBLE (3685 2860);
FORCEPROP 1 LAST SIZE 1B
J 0
(3750 2750);
DISPLAY 0.872340 (3750 2750);
PAINT AQUA (3750 2750);
DISPLAY INVISIBLE (3750 2750);
FORCEPROP 1 LAST VOLTAGE 0.0V
J 0
(3630 2757);
DISPLAY 0.340426 (3630 2757);
PAINT SKYBLUE (3630 2757);
DISPLAY INVISIBLE (3630 2757);
FORCEPROP 1 LAST PATH I54
J 0
(3750 2800);
DISPLAY 0.872340 (3750 2800);
PAINT AQUA (3750 2800);
DISPLAY INVISIBLE (3750 2800);
FORCEPROP 2 LAST CDS_LIB mstr_symbols
J 0
(3675 2800);
PAINT ORANGE (3675 2800);
DISPLAY INVISIBLE (3675 2800);
FORCEPROP 1 LAST BODY_TYPE PLUMBING
J 0
(3630 2757);
DISPLAY 0.340426 (3630 2757);
PAINT GREEN (3630 2757);
DISPLAY INVISIBLE (3630 2757);
FORCEPROP 1 LAST HDL_POWER GND
J 0
(3675 2950);
DISPLAY 0.872340 (3675 2950);
PAINT GREEN (3675 2950);
DISPLAY INVISIBLE (3675 2950);
FORCEADD GND..1
(3200 2475);
FORCEPROP 3 LASTPIN (3200 2525) SIG_NAME GND\g
J 0
(3210 2535);
DISPLAY 0.659574 (3210 2535);
PAINT MONO (3210 2535);
DISPLAY INVISIBLE (3210 2535);
FORCEPROP 1 LAST HDL_POWER GND
J 0
(3200 2625);
DISPLAY 0.872340 (3200 2625);
PAINT GREEN (3200 2625);
DISPLAY INVISIBLE (3200 2625);
FORCEPROP 1 LAST BODY_TYPE PLUMBING
J 0
(3155 2432);
DISPLAY 0.340426 (3155 2432);
PAINT GREEN (3155 2432);
DISPLAY INVISIBLE (3155 2432);
FORCEPROP 1 LAST PATH I55
J 0
(3275 2475);
DISPLAY 0.872340 (3275 2475);
PAINT AQUA (3275 2475);
DISPLAY INVISIBLE (3275 2475);
FORCEPROP 1 LAST SIZE 1B
J 0
(3275 2425);
DISPLAY 0.872340 (3275 2425);
PAINT AQUA (3275 2425);
DISPLAY INVISIBLE (3275 2425);
FORCEPROP 2 LAST CDS_LIB mstr_symbols
J 0
(3200 2475);
PAINT ORANGE (3200 2475);
DISPLAY INVISIBLE (3200 2475);
FORCEPROP 1 LAST VOLTAGE 0.0V
J 0
(3155 2432);
DISPLAY 0.340426 (3155 2432);
PAINT SKYBLUE (3155 2432);
DISPLAY INVISIBLE (3155 2432);
FORCEADD RES..2
(3200 2700);
FORCEPROP 1 LAST TOLERANCE 1%
J 0
(3245 2725);
DISPLAY 0.617021 (3245 2725);
PAINT SKYBLUE (3245 2725);
FORCEPROP 1 LAST VALUE 4.75K
J 0
(3245 2775);
DISPLAY 0.617021 (3245 2775);
PAINT SKYBLUE (3245 2775);
FORCEPROP 1 LAST WATTAGE 1/16W
J 0
(3240 2675);
DISPLAY 0.617021 (3240 2675);
PAINT SKYBLUE (3240 2675);
FORCEPROP 1 LASTPIN (3200 2600) $PN 2
J 0
(3205 2610);
DISPLAY 0.617021 (3205 2610);
PAINT ORANGE (3205 2610);
FORCEPROP 1 LAST LOCATION R8G23
J 0
(3245 2825);
DISPLAY 0.617021 (3245 2825);
PAINT AQUA (3245 2825);
FORCEPROP 1 LAST PACK_TYPE 0402
J 0
(3240 2525);
DISPLAY 0.617021 (3240 2525);
PAINT SKYBLUE (3240 2525);
FORCEPROP 1 LAST MATERIAL CHIP
J 0
(3240 2625);
DISPLAY 0.617021 (3240 2625);
PAINT SKYBLUE (3240 2625);
FORCEPROP 1 LASTPIN (3200 2800) $PN 1
J 0
(3205 2762);
DISPLAY 0.617021 (3205 2762);
PAINT ORANGE (3205 2762);
FORCEPROP 1 LAST PART_NUMBER G21796-072
J 0
(3240 2575);
DISPLAY 0.617021 (3240 2575);
PAINT BLUE (3240 2575);
FORCEPROP 2 LAST ROOM BMC_DEBUG_HEADER
J 0
(3150 2800);
DISPLAY 1.021277 (3150 2800);
PAINT ORANGE (3150 2800);
DISPLAY INVISIBLE (3150 2800);
FORCEPROP 2 LAST CDS_LIB mstr_discrete
J 0
(3200 2700);
PAINT ORANGE (3200 2700);
DISPLAY INVISIBLE (3200 2700);
FORCEPROP 2 LAST CDS_LOCATION R8G23
J 0
(3245 2825);
DISPLAY 0.617021 (3245 2825);
PAINT AQUA (3245 2825);
DISPLAY INVISIBLE (3245 2825);
FORCEPROP 1 LAST PATH I56
J 0
(3250 2875);
DISPLAY 0.978723 (3250 2875);
PAINT WHITE (3250 2875);
DISPLAY INVISIBLE (3250 2875);
FORCEPROP 2 LAST SEC 1
J 0
(3250 2925);
DISPLAY 0.680851 (3250 2925);
PAINT MONO (3250 2925);
DISPLAY INVISIBLE (3250 2925);
FORCEPROP 2 LAST SEC_TYPE 0402
J 0
(3250 2925);
DISPLAY 1.021277 (3250 2925);
PAINT ORANGE (3250 2925);
DISPLAY INVISIBLE (3250 2925);
FORCEADD OFFPAGE..5
(1400 3225);
FORCEPROP 2 LAST $XR0 189 
J 0
(1145 3225);
DISPLAY 0.638298 (1145 3225);
PAINT MONO (1145 3225);
FORCEPROP 2 LAST CDS_LIB mstr_standard
J 0
(1400 3225);
PAINT ORANGE (1400 3225);
DISPLAY INVISIBLE (1400 3225);
FORCEPROP 2 LAST PATH I57
J 0
(1150 3275);
DISPLAY 1.021277 (1150 3275);
PAINT ORANGE (1150 3275);
DISPLAY INVISIBLE (1150 3275);
FORCEPROP 1 LAST OFFPAGE TRUE
J 0
(1725 3100);
DISPLAY 0.872340 (1725 3100);
PAINT GREEN (1725 3100);
DISPLAY INVISIBLE (1725 3100);
FORCEPROP 1 LAST COMMENT_BODY TRUE
J 0
(1500 3150);
DISPLAY 0.872340 (1500 3150);
PAINT GREEN (1500 3150);
DISPLAY INVISIBLE (1500 3150);
FORCEADD OFFPAGE..1
(1400 3175);
FORCEPROP 2 LAST $XR0 189 
J 0
(1118 3175);
DISPLAY 0.638298 (1118 3175);
PAINT MONO (1118 3175);
FORCEPROP 2 LAST CDS_LIB mstr_standard
J 0
(1400 3175);
PAINT ORANGE (1400 3175);
DISPLAY INVISIBLE (1400 3175);
FORCEPROP 2 LAST PATH I58
J 0
(1150 3225);
DISPLAY 1.021277 (1150 3225);
PAINT ORANGE (1150 3225);
DISPLAY INVISIBLE (1150 3225);
FORCEPROP 1 LAST OFFPAGE TRUE
J 0
(1725 3050);
DISPLAY 0.872340 (1725 3050);
PAINT GREEN (1725 3050);
DISPLAY INVISIBLE (1725 3050);
FORCEPROP 1 LAST COMMENT_BODY TRUE
J 0
(1525 3075);
DISPLAY 0.872340 (1525 3075);
PAINT GREEN (1525 3075);
DISPLAY INVISIBLE (1525 3075);
FORCEADD OFFPAGE..1
(1400 3125);
FORCEPROP 2 LAST $XR0 189 
J 0
(1118 3125);
DISPLAY 0.638298 (1118 3125);
PAINT MONO (1118 3125);
FORCEPROP 2 LAST CDS_LIB mstr_standard
J 0
(1400 3125);
PAINT ORANGE (1400 3125);
DISPLAY INVISIBLE (1400 3125);
FORCEPROP 2 LAST PATH I59
J 0
(1150 3175);
DISPLAY 1.021277 (1150 3175);
PAINT ORANGE (1150 3175);
DISPLAY INVISIBLE (1150 3175);
FORCEPROP 1 LAST OFFPAGE TRUE
J 0
(1725 3000);
DISPLAY 0.872340 (1725 3000);
PAINT GREEN (1725 3000);
DISPLAY INVISIBLE (1725 3000);
FORCEPROP 1 LAST COMMENT_BODY TRUE
J 0
(1525 3025);
DISPLAY 0.872340 (1525 3025);
PAINT GREEN (1525 3025);
DISPLAY INVISIBLE (1525 3025);
FORCEADD OFFPAGE..2
(-1375 4400);
FORCEPROP 2 LAST $XR0 189 
J 0
(-1096 4400);
DISPLAY 0.638298 (-1096 4400);
PAINT MONO (-1096 4400);
FORCEPROP 2 LAST CDS_LIB mstr_standard
J 0
(-1375 4400);
PAINT ORANGE (-1375 4400);
DISPLAY INVISIBLE (-1375 4400);
FORCEPROP 2 LAST PATH I6
J 0
(-1175 4450);
DISPLAY 1.021277 (-1175 4450);
PAINT ORANGE (-1175 4450);
DISPLAY INVISIBLE (-1175 4450);
FORCEPROP 1 LAST OFFPAGE TRUE
J 0
(-1050 4275);
DISPLAY 0.872340 (-1050 4275);
PAINT GREEN (-1050 4275);
DISPLAY INVISIBLE (-1050 4275);
FORCEPROP 1 LAST COMMENT_BODY TRUE
J 0
(-1420 4305);
DISPLAY 0.872340 (-1420 4305);
PAINT GREEN (-1420 4305);
DISPLAY INVISIBLE (-1420 4305);
FORCEADD OFFPAGE..1
(1400 3025);
FORCEPROP 2 LAST $XR0 189 
J 0
(1118 3025);
DISPLAY 0.638298 (1118 3025);
PAINT MONO (1118 3025);
FORCEPROP 2 LAST PATH I60
J 0
(1150 3075);
DISPLAY 1.021277 (1150 3075);
PAINT ORANGE (1150 3075);
DISPLAY INVISIBLE (1150 3075);
FORCEPROP 2 LAST CDS_LIB mstr_standard
J 0
(1400 3025);
PAINT ORANGE (1400 3025);
DISPLAY INVISIBLE (1400 3025);
FORCEPROP 1 LAST OFFPAGE TRUE
J 0
(1725 2900);
DISPLAY 0.872340 (1725 2900);
PAINT GREEN (1725 2900);
DISPLAY INVISIBLE (1725 2900);
FORCEPROP 1 LAST COMMENT_BODY TRUE
J 0
(1525 2925);
DISPLAY 0.872340 (1525 2925);
PAINT GREEN (1525 2925);
DISPLAY INVISIBLE (1525 2925);
FORCEADD OFFPAGE..1
(1400 3075);
FORCEPROP 2 LAST $XR5 239 
J 0
(518 3075);
DISPLAY 0.638298 (518 3075);
PAINT MONO (518 3075);
FORCEPROP 2 LAST $XR4 237 
J 0
(638 3075);
DISPLAY 0.638298 (638 3075);
PAINT MONO (638 3075);
FORCEPROP 2 LAST $XR3 196 
J 0
(758 3075);
DISPLAY 0.638298 (758 3075);
PAINT MONO (758 3075);
FORCEPROP 2 LAST $XR2 191 
J 0
(878 3075);
DISPLAY 0.638298 (878 3075);
PAINT MONO (878 3075);
FORCEPROP 2 LAST $XR1 101 
J 0
(998 3075);
DISPLAY 0.638298 (998 3075);
PAINT MONO (998 3075);
FORCEPROP 2 LAST $XR0 240 
J 0
(1118 3075);
DISPLAY 0.638298 (1118 3075);
PAINT MONO (1118 3075);
FORCEPROP 2 LAST PATH I61
J 0
(1150 3125);
DISPLAY 1.021277 (1150 3125);
PAINT ORANGE (1150 3125);
DISPLAY INVISIBLE (1150 3125);
FORCEPROP 2 LAST CDS_LIB mstr_standard
J 0
(1400 3075);
PAINT ORANGE (1400 3075);
DISPLAY INVISIBLE (1400 3075);
FORCEPROP 1 LAST OFFPAGE TRUE
J 0
(1725 2950);
DISPLAY 0.872340 (1725 2950);
PAINT GREEN (1725 2950);
DISPLAY INVISIBLE (1725 2950);
FORCEPROP 1 LAST COMMENT_BODY TRUE
J 0
(1525 2975);
DISPLAY 0.872340 (1525 2975);
PAINT GREEN (1525 2975);
DISPLAY INVISIBLE (1525 2975);
FORCEADD OFFPAGE..1
(1400 2925);
FORCEPROP 2 LAST $XR0 189 
J 0
(1118 2925);
DISPLAY 0.638298 (1118 2925);
PAINT MONO (1118 2925);
FORCEPROP 2 LAST CDS_LIB mstr_standard
J 0
(1400 2925);
PAINT ORANGE (1400 2925);
DISPLAY INVISIBLE (1400 2925);
FORCEPROP 2 LAST PATH I62
J 0
(1150 2975);
DISPLAY 1.021277 (1150 2975);
PAINT ORANGE (1150 2975);
DISPLAY INVISIBLE (1150 2975);
FORCEPROP 1 LAST OFFPAGE TRUE
J 0
(1725 2800);
DISPLAY 0.872340 (1725 2800);
PAINT GREEN (1725 2800);
DISPLAY INVISIBLE (1725 2800);
FORCEPROP 1 LAST COMMENT_BODY TRUE
J 0
(1525 2825);
DISPLAY 0.872340 (1525 2825);
PAINT GREEN (1525 2825);
DISPLAY INVISIBLE (1525 2825);
FORCEADD RES..1
(2050 3225);
FORCEPROP 1 LAST PART_NUMBER G21497-005
J 0
(2200 3225);
DISPLAY 0.617021 (2200 3225);
PAINT BLUE (2200 3225);
FORCEPROP 1 LASTPIN (2150 3225) $PN 2
J 0
(2112 3237);
DISPLAY 0.617021 (2112 3237);
PAINT ORANGE (2112 3237);
FORCEPROP 1 LAST LOCATION R7G21
J 0
(2000 3275);
DISPLAY 0.617021 (2000 3275);
PAINT AQUA (2000 3275);
FORCEPROP 1 LASTPIN (1950 3225) $PN 1
J 0
(1962 3237);
DISPLAY 0.617021 (1962 3237);
PAINT ORANGE (1962 3237);
FORCEPROP 1 LAST MATERIAL CHIP
J 0
(2025 3175);
DISPLAY 0.617021 (2025 3175);
PAINT SKYBLUE (2025 3175);
FORCEPROP 1 LAST PACK_TYPE 0402
J 0
(2125 3175);
DISPLAY 0.617021 (2125 3175);
PAINT SKYBLUE (2125 3175);
FORCEPROP 1 LAST VALUE 0.0
J 2
(1875 3225);
DISPLAY 0.617021 (1875 3225);
PAINT SKYBLUE (1875 3225);
FORCEPROP 1 LAST TOLERANCE 5%
J 0
(1900 3225);
DISPLAY 0.617021 (1900 3225);
PAINT SKYBLUE (1900 3225);
FORCEPROP 1 LAST WATTAGE 1/16W
J 2
(2000 3175);
DISPLAY 0.617021 (2000 3175);
PAINT SKYBLUE (2000 3175);
FORCEPROP 2 LAST CDS_LOCATION R7G21
J 0
(2000 3275);
DISPLAY 0.617021 (2000 3275);
PAINT AQUA (2000 3275);
DISPLAY INVISIBLE (2000 3275);
FORCEPROP 2 LAST CDS_LIB mstr_discrete
J 0
(2050 3225);
PAINT ORANGE (2050 3225);
DISPLAY INVISIBLE (2050 3225);
FORCEPROP 2 LAST ROOM BMC_DEBUG_HEADER
J 0
(2000 3325);
DISPLAY 1.021277 (2000 3325);
PAINT ORANGE (2000 3325);
DISPLAY INVISIBLE (2000 3325);
FORCEPROP 1 LAST PATH I63
J 0
(2000 3375);
DISPLAY 0.978723 (2000 3375);
PAINT WHITE (2000 3375);
DISPLAY INVISIBLE (2000 3375);
FORCEPROP 2 LAST SEC 1
J 0
(2000 3425);
DISPLAY 0.680851 (2000 3425);
PAINT MONO (2000 3425);
DISPLAY INVISIBLE (2000 3425);
FORCEPROP 2 LAST SEC_TYPE 0402
J 0
(2000 3425);
DISPLAY 1.021277 (2000 3425);
PAINT ORANGE (2000 3425);
DISPLAY INVISIBLE (2000 3425);
FORCEPROP 2 LAST BOM_COST DEBUG
J 0
(2000 3375);
DISPLAY 1.021277 (2000 3375);
PAINT ORANGE (2000 3375);
DISPLAY INVISIBLE (2000 3375);
FORCEADD RES..1
(2425 3175);
FORCEPROP 1 LAST MATERIAL CHIP
J 0
(2400 3125);
DISPLAY 0.617021 (2400 3125);
PAINT SKYBLUE (2400 3125);
FORCEPROP 1 LAST WATTAGE 1/16W
J 2
(2375 3125);
DISPLAY 0.617021 (2375 3125);
PAINT SKYBLUE (2375 3125);
FORCEPROP 1 LAST TOLERANCE 5%
J 0
(2275 3175);
DISPLAY 0.617021 (2275 3175);
PAINT SKYBLUE (2275 3175);
FORCEPROP 1 LAST VALUE 0.0
J 2
(2250 3175);
DISPLAY 0.617021 (2250 3175);
PAINT SKYBLUE (2250 3175);
FORCEPROP 1 LASTPIN (2325 3175) $PN 1
J 0
(2337 3187);
DISPLAY 0.617021 (2337 3187);
PAINT ORANGE (2337 3187);
FORCEPROP 1 LAST LOCATION R8G19
J 0
(2375 3225);
DISPLAY 0.617021 (2375 3225);
PAINT AQUA (2375 3225);
FORCEPROP 1 LAST PART_NUMBER G21497-005
J 0
(2575 3175);
DISPLAY 0.617021 (2575 3175);
PAINT BLUE (2575 3175);
FORCEPROP 1 LAST PACK_TYPE 0402
J 0
(2500 3125);
DISPLAY 0.617021 (2500 3125);
PAINT SKYBLUE (2500 3125);
FORCEPROP 1 LASTPIN (2525 3175) $PN 2
J 0
(2487 3187);
DISPLAY 0.617021 (2487 3187);
PAINT ORANGE (2487 3187);
FORCEPROP 2 LAST SEC_TYPE 0402
J 0
(2375 3375);
DISPLAY 1.021277 (2375 3375);
PAINT ORANGE (2375 3375);
DISPLAY INVISIBLE (2375 3375);
FORCEPROP 2 LAST SEC 1
J 0
(2375 3375);
DISPLAY 0.680851 (2375 3375);
PAINT MONO (2375 3375);
DISPLAY INVISIBLE (2375 3375);
FORCEPROP 2 LAST BOM_COST DEBUG
J 0
(2375 3325);
DISPLAY 1.021277 (2375 3325);
PAINT ORANGE (2375 3325);
DISPLAY INVISIBLE (2375 3325);
FORCEPROP 1 LAST PATH I64
J 0
(2375 3325);
DISPLAY 0.978723 (2375 3325);
PAINT WHITE (2375 3325);
DISPLAY INVISIBLE (2375 3325);
FORCEPROP 2 LAST ROOM BMC_DEBUG_HEADER
J 0
(2375 3275);
DISPLAY 1.021277 (2375 3275);
PAINT ORANGE (2375 3275);
DISPLAY INVISIBLE (2375 3275);
FORCEPROP 2 LAST CDS_LOCATION R8G19
J 0
(2375 3225);
DISPLAY 0.617021 (2375 3225);
PAINT AQUA (2375 3225);
DISPLAY INVISIBLE (2375 3225);
FORCEPROP 2 LAST CDS_LIB mstr_discrete
J 0
(2425 3175);
PAINT ORANGE (2425 3175);
DISPLAY INVISIBLE (2425 3175);
FORCEADD RES..1
(2525 3025);
FORCEPROP 1 LAST WATTAGE 1/16W
J 2
(2475 2975);
DISPLAY 0.617021 (2475 2975);
PAINT SKYBLUE (2475 2975);
FORCEPROP 1 LAST VALUE 0.0
J 2
(2350 3025);
DISPLAY 0.617021 (2350 3025);
PAINT SKYBLUE (2350 3025);
FORCEPROP 1 LAST PART_NUMBER G21497-005
J 0
(2675 3025);
DISPLAY 0.617021 (2675 3025);
PAINT BLUE (2675 3025);
FORCEPROP 1 LAST PACK_TYPE 0402
J 0
(2600 2975);
DISPLAY 0.617021 (2600 2975);
PAINT SKYBLUE (2600 2975);
FORCEPROP 1 LASTPIN (2625 3025) $PN 2
J 0
(2587 3037);
DISPLAY 0.617021 (2587 3037);
PAINT ORANGE (2587 3037);
FORCEPROP 1 LAST LOCATION R8G21
J 0
(2475 3075);
DISPLAY 0.617021 (2475 3075);
PAINT AQUA (2475 3075);
FORCEPROP 1 LAST MATERIAL CHIP
J 0
(2500 2975);
DISPLAY 0.617021 (2500 2975);
PAINT SKYBLUE (2500 2975);
FORCEPROP 1 LAST TOLERANCE 5%
J 0
(2375 3025);
DISPLAY 0.617021 (2375 3025);
PAINT SKYBLUE (2375 3025);
FORCEPROP 1 LASTPIN (2425 3025) $PN 1
J 0
(2437 3037);
DISPLAY 0.617021 (2437 3037);
PAINT ORANGE (2437 3037);
FORCEPROP 2 LAST ROOM BMC_DEBUG_HEADER
J 0
(2475 3125);
DISPLAY 1.021277 (2475 3125);
PAINT ORANGE (2475 3125);
DISPLAY INVISIBLE (2475 3125);
FORCEPROP 1 LAST PATH I65
J 0
(2475 3175);
DISPLAY 0.978723 (2475 3175);
PAINT WHITE (2475 3175);
DISPLAY INVISIBLE (2475 3175);
FORCEPROP 2 LAST SEC 1
J 0
(2475 3225);
DISPLAY 0.680851 (2475 3225);
PAINT MONO (2475 3225);
DISPLAY INVISIBLE (2475 3225);
FORCEPROP 2 LAST SEC_TYPE 0402
J 0
(2475 3225);
DISPLAY 1.021277 (2475 3225);
PAINT ORANGE (2475 3225);
DISPLAY INVISIBLE (2475 3225);
FORCEPROP 2 LAST BOM_COST DEBUG
J 0
(2475 3175);
DISPLAY 1.021277 (2475 3175);
PAINT ORANGE (2475 3175);
DISPLAY INVISIBLE (2475 3175);
FORCEPROP 2 LAST CDS_LOCATION R8G21
J 0
(2475 3075);
DISPLAY 0.617021 (2475 3075);
PAINT AQUA (2475 3075);
DISPLAY INVISIBLE (2475 3075);
FORCEPROP 2 LAST CDS_LIB mstr_discrete
J 0
(2525 3025);
PAINT ORANGE (2525 3025);
DISPLAY INVISIBLE (2525 3025);
FORCEADD RES..1
(2850 2925);
FORCEPROP 1 LAST WATTAGE 1/16W
J 2
(2800 2875);
DISPLAY 0.617021 (2800 2875);
PAINT SKYBLUE (2800 2875);
FORCEPROP 1 LAST LOCATION R8G22
J 0
(2800 2975);
DISPLAY 0.617021 (2800 2975);
PAINT AQUA (2800 2975);
FORCEPROP 1 LAST MATERIAL CHIP
J 0
(2825 2875);
DISPLAY 0.617021 (2825 2875);
PAINT SKYBLUE (2825 2875);
FORCEPROP 1 LAST PART_NUMBER G21497-005
J 0
(2800 2850);
DISPLAY 0.617021 (2800 2850);
PAINT BLUE (2800 2850);
FORCEPROP 1 LAST VALUE 0.0
J 2
(2675 2925);
DISPLAY 0.617021 (2675 2925);
PAINT SKYBLUE (2675 2925);
FORCEPROP 1 LAST TOLERANCE 5%
J 0
(2700 2925);
DISPLAY 0.617021 (2700 2925);
PAINT SKYBLUE (2700 2925);
FORCEPROP 1 LASTPIN (2950 2925) $PN 2
J 0
(2912 2937);
DISPLAY 0.617021 (2912 2937);
PAINT ORANGE (2912 2937);
FORCEPROP 1 LAST PACK_TYPE 0402
J 0
(2925 2875);
DISPLAY 0.617021 (2925 2875);
PAINT SKYBLUE (2925 2875);
FORCEPROP 1 LASTPIN (2750 2925) $PN 1
J 0
(2762 2937);
DISPLAY 0.617021 (2762 2937);
PAINT ORANGE (2762 2937);
FORCEPROP 2 LAST CDS_LIB mstr_discrete
J 0
(2850 2925);
PAINT ORANGE (2850 2925);
DISPLAY INVISIBLE (2850 2925);
FORCEPROP 2 LAST CDS_LOCATION R8G22
J 0
(2800 2975);
DISPLAY 0.617021 (2800 2975);
PAINT AQUA (2800 2975);
DISPLAY INVISIBLE (2800 2975);
FORCEPROP 2 LAST ROOM BMC_DEBUG_HEADER
J 0
(2800 3025);
DISPLAY 1.021277 (2800 3025);
PAINT ORANGE (2800 3025);
DISPLAY INVISIBLE (2800 3025);
FORCEPROP 1 LAST PATH I66
J 0
(2800 3075);
DISPLAY 0.978723 (2800 3075);
PAINT WHITE (2800 3075);
DISPLAY INVISIBLE (2800 3075);
FORCEPROP 2 LAST BOM_COST DEBUG
J 0
(2800 3075);
DISPLAY 1.021277 (2800 3075);
PAINT ORANGE (2800 3075);
DISPLAY INVISIBLE (2800 3075);
FORCEPROP 2 LAST SEC_TYPE 0402
J 0
(2800 3125);
DISPLAY 1.021277 (2800 3125);
PAINT ORANGE (2800 3125);
DISPLAY INVISIBLE (2800 3125);
FORCEPROP 2 LAST SEC 1
J 0
(2800 3125);
DISPLAY 0.680851 (2800 3125);
PAINT MONO (2800 3125);
DISPLAY INVISIBLE (2800 3125);
FORCEADD TTL3126..3
(800 4300);
FORCEPROP 1 LAST POWER_GROUP VCC=P3V3_STBY;GND=GND
J 0
(650 3775);
DISPLAY 0.617021 (650 3775);
PAINT ORANGE (650 3775);
FORCEPROP 1 LAST PART_NUMBER D18317-001
J 0
(650 3825);
DISPLAY 0.617021 (650 3825);
PAINT BLUE (650 3825);
FORCEPROP 1 LAST VALUE 74CBTLV3126
J 0
(650 4775);
DISPLAY 0.617021 (650 4775);
PAINT SKYBLUE (650 4775);
FORCEPROP 1 LAST MATERIAL IC
J 0
(650 4825);
DISPLAY 0.617021 (650 4825);
PAINT SKYBLUE (650 4825);
FORCEPROP 1 LAST LOCATION U1L10
J 0
(650 4875);
DISPLAY 0.617021 (650 4875);
PAINT AQUA (650 4875);
FORCEPROP 0 LAST ROOM DEBUG
J 0
(650 4975);
DISPLAY 1.021277 (650 4975);
PAINT ORANGE (650 4975);
DISPLAY INVISIBLE (650 4975);
FORCEPROP 1 LAST HAS_FIXED_SIZE 4B
J 0
(650 3725);
DISPLAY 1.595745 (650 3725);
PAINT BLUE (650 3725);
DISPLAY INVISIBLE (650 3725);
FORCEPROP 1 LAST PACK_TYPE QFNLF
J 0
(650 4925);
DISPLAY 1.595745 (650 4925);
PAINT SKYBLUE (650 4925);
DISPLAY INVISIBLE (650 4925);
FORCEPROP 1 LAST PATH I67
J 0
(1100 4825);
DISPLAY 0.978723 (1100 4825);
PAINT BLUE (1100 4825);
DISPLAY INVISIBLE (1100 4825);
FORCEPROP 2 LAST CDS_LIB mstr_ttl
J 0
(800 4300);
DISPLAY INVISIBLE (800 4300);
FORCEADD P3V3_STBY..1
(775 3700);
FORCEPROP 3 LASTPIN (775 3650) SIG_NAME P3V3_STBY\g
J 0
(785 3660);
DISPLAY 0.659574 (785 3660);
PAINT MONO (785 3660);
DISPLAY INVISIBLE (785 3660);
FORCEPROP 2 LAST CDS_LIB mstr_symbols
J 0
(775 3700);
DISPLAY INVISIBLE (775 3700);
FORCEPROP 1 LAST PATH I68
J 0
(820 3702);
DISPLAY 0.340426 (820 3702);
PAINT GREEN (820 3702);
DISPLAY INVISIBLE (820 3702);
FORCEPROP 1 LAST VOLTAGE +3.3V
J 0
(975 3850);
DISPLAY 1.021277 (975 3850);
PAINT SKYBLUE (975 3850);
DISPLAY INVISIBLE (975 3850);
FORCEPROP 1 LAST SIZE 1B
J 0
(820 3722);
DISPLAY 0.340426 (820 3722);
PAINT GREEN (820 3722);
DISPLAY INVISIBLE (820 3722);
FORCEPROP 1 LAST BODY_TYPE PLUMBING
J 0
(730 3657);
DISPLAY 0.340426 (730 3657);
PAINT GREEN (730 3657);
DISPLAY INVISIBLE (730 3657);
FORCEPROP 1 LAST HDL_POWER P3V3_STBY
J 0
(475 3575);
DISPLAY 0.872340 (475 3575);
PAINT ORANGE (475 3575);
DISPLAY INVISIBLE (475 3575);
FORCEADD CAP..1
(775 3525);
FORCEPROP 1 LAST MATERIAL X6S
J 0
(825 3425);
DISPLAY 0.617021 (825 3425);
PAINT SKYBLUE (825 3425);
FORCEPROP 1 LAST PART_NUMBER D97712-011
J 0
(825 3375);
DISPLAY 0.617021 (825 3375);
PAINT BLUE (825 3375);
FORCEPROP 1 LAST VOLTAGE 16V
J 0
(825 3525);
DISPLAY 0.617021 (825 3525);
PAINT SKYBLUE (825 3525);
FORCEPROP 1 LAST TOLERANCE 10%
J 0
(825 3475);
DISPLAY 0.617021 (825 3475);
PAINT SKYBLUE (825 3475);
FORCEPROP 1 LAST PACK_TYPE 0402
J 0
(825 3325);
DISPLAY 0.617021 (825 3325);
PAINT SKYBLUE (825 3325);
FORCEPROP 1 LAST VALUE 1.0UF
J 0
(825 3575);
DISPLAY 0.617021 (825 3575);
PAINT SKYBLUE (825 3575);
FORCEPROP 1 LAST LOCATION C1L119
J 0
(825 3625);
DISPLAY 0.617021 (825 3625);
PAINT AQUA (825 3625);
FORCEPROP 0 LAST ROOM DEBUG
J 0
(825 3725);
DISPLAY 1.021277 (825 3725);
PAINT ORANGE (825 3725);
DISPLAY INVISIBLE (825 3725);
FORCEPROP 1 LAST PATH I69
J 0
(825 3675);
DISPLAY 0.978723 (825 3675);
PAINT WHITE (825 3675);
DISPLAY INVISIBLE (825 3675);
FORCEPROP 2 LAST CDS_LIB mstr_discrete
J 0
(775 3525);
DISPLAY INVISIBLE (775 3525);
FORCEPROP 1 LASTPIN (775 3425) $PN 2
J 0
(785 3405);
DISPLAY 0.787234 (785 3405);
PAINT ORANGE (785 3405);
DISPLAY INVISIBLE (785 3405);
FORCEPROP 1 LASTPIN (775 3625) $PN 1
J 0
(785 3605);
DISPLAY 0.787234 (785 3605);
PAINT ORANGE (785 3605);
DISPLAY INVISIBLE (785 3605);
FORCEADD RES..1
(-2100 4775);
FORCEPROP 1 LAST PART_NUMBER G21497-005
J 0
(-1950 4775);
DISPLAY 0.617021 (-1950 4775);
PAINT BLUE (-1950 4775);
FORCEPROP 1 LAST PACK_TYPE 0402
J 0
(-2025 4725);
DISPLAY 0.617021 (-2025 4725);
PAINT SKYBLUE (-2025 4725);
FORCEPROP 1 LAST VALUE 0.0
J 2
(-2275 4775);
DISPLAY 0.617021 (-2275 4775);
PAINT SKYBLUE (-2275 4775);
FORCEPROP 1 LASTPIN (-2000 4775) $PN 2
J 0
(-2038 4787);
DISPLAY 0.617021 (-2038 4787);
PAINT ORANGE (-2038 4787);
FORCEPROP 1 LAST LOCATION R8G10
J 0
(-2150 4825);
DISPLAY 0.617021 (-2150 4825);
PAINT AQUA (-2150 4825);
FORCEPROP 1 LAST MATERIAL CHIP
J 0
(-2150 4725);
DISPLAY 0.617021 (-2150 4725);
PAINT SKYBLUE (-2150 4725);
FORCEPROP 1 LASTPIN (-2200 4775) $PN 1
J 0
(-2188 4787);
DISPLAY 0.617021 (-2188 4787);
PAINT ORANGE (-2188 4787);
FORCEPROP 1 LAST TOLERANCE 5%
J 0
(-2250 4775);
DISPLAY 0.617021 (-2250 4775);
PAINT SKYBLUE (-2250 4775);
FORCEPROP 1 LAST WATTAGE 1/16W
J 2
(-2175 4725);
DISPLAY 0.617021 (-2175 4725);
PAINT SKYBLUE (-2175 4725);
FORCEPROP 2 LAST SEC_TYPE 0402
J 0
(-2150 4975);
DISPLAY 1.021277 (-2150 4975);
PAINT ORANGE (-2150 4975);
DISPLAY INVISIBLE (-2150 4975);
FORCEPROP 2 LAST SEC 1
J 0
(-2150 4975);
DISPLAY 0.680851 (-2150 4975);
PAINT MONO (-2150 4975);
DISPLAY INVISIBLE (-2150 4975);
FORCEPROP 2 LAST BOM_COST DEBUG
J 0
(-2150 4925);
DISPLAY 1.021277 (-2150 4925);
PAINT ORANGE (-2150 4925);
DISPLAY INVISIBLE (-2150 4925);
FORCEPROP 1 LAST PATH I7
J 0
(-2150 4925);
DISPLAY 0.978723 (-2150 4925);
PAINT WHITE (-2150 4925);
DISPLAY INVISIBLE (-2150 4925);
FORCEPROP 2 LAST CDS_LIB mstr_discrete
J 0
(-2100 4775);
PAINT ORANGE (-2100 4775);
DISPLAY INVISIBLE (-2100 4775);
FORCEPROP 2 LAST CDS_LOCATION R8G10
J 0
(-2150 4825);
DISPLAY 0.617021 (-2150 4825);
PAINT AQUA (-2150 4825);
DISPLAY INVISIBLE (-2150 4825);
FORCEPROP 2 LAST ROOM BMC_DEBUG_HEADER
J 0
(-2150 4875);
DISPLAY 1.021277 (-2150 4875);
PAINT ORANGE (-2150 4875);
DISPLAY INVISIBLE (-2150 4875);
FORCEADD GND..1
(775 3350);
FORCEPROP 3 LASTPIN (775 3400) SIG_NAME GND\g
J 0
(785 3410);
DISPLAY 0.659574 (785 3410);
PAINT MONO (785 3410);
DISPLAY INVISIBLE (785 3410);
FORCEPROP 2 LAST CDS_LIB mstr_symbols
J 0
(775 3350);
DISPLAY INVISIBLE (775 3350);
FORCEPROP 1 LAST PATH I70
J 0
(850 3350);
DISPLAY 0.872340 (850 3350);
PAINT AQUA (850 3350);
DISPLAY INVISIBLE (850 3350);
FORCEPROP 1 LAST VOLTAGE 0.0V
J 0
(730 3307);
DISPLAY 0.340426 (730 3307);
PAINT SKYBLUE (730 3307);
DISPLAY INVISIBLE (730 3307);
FORCEPROP 1 LAST SIZE 1B
J 0
(850 3300);
DISPLAY 2.382979 (850 3300);
PAINT GREEN (850 3300);
DISPLAY INVISIBLE (850 3300);
FORCEPROP 1 LAST BODY_TYPE PLUMBING
J 0
(730 3307);
DISPLAY 0.340426 (730 3307);
PAINT GREEN (730 3307);
DISPLAY INVISIBLE (730 3307);
FORCEPROP 1 LAST HDL_POWER GND
J 0
(775 3500);
PAINT GREEN (775 3500);
DISPLAY INVISIBLE (775 3500);
FORCEADD OFFPAGE..1
(-700 3800);
FORCEPROP 2 LAST $XR3 255 
J 0
(-952 3728);
DISPLAY 0.638298 (-952 3728);
PAINT MONO (-952 3728);
FORCEPROP 2 LAST $XR2 254 
J 0
(-952 3836);
DISPLAY 0.638298 (-952 3836);
PAINT MONO (-952 3836);
FORCEPROP 2 LAST $XR1 189 
J 0
(-952 3764);
DISPLAY 0.638298 (-952 3764);
PAINT MONO (-952 3764);
FORCEPROP 2 LAST $XR0 148 
J 0
(-952 3800);
DISPLAY 0.638298 (-952 3800);
PAINT MONO (-952 3800);
FORCEPROP 2 LAST CDS_LIB mstr_standard
J 0
(-700 3800);
DISPLAY INVISIBLE (-700 3800);
FORCEPROP 2 LAST PATH I71
J 0
(-650 3875);
DISPLAY 1.021277 (-650 3875);
PAINT ORANGE (-650 3875);
DISPLAY INVISIBLE (-650 3875);
FORCEPROP 1 LAST OFFPAGE TRUE
J 0
(-375 3675);
DISPLAY 0.872340 (-375 3675);
PAINT GREEN (-375 3675);
DISPLAY INVISIBLE (-375 3675);
FORCEPROP 1 LAST COMMENT_BODY TRUE
J 0
(-575 3700);
DISPLAY 0.872340 (-575 3700);
PAINT GREEN (-575 3700);
DISPLAY INVISIBLE (-575 3700);
FORCEADD OFFPAGE..2
(1625 4650);
FORCEPROP 2 LAST $XR0 189 
J 0
(1814 4650);
DISPLAY 0.638298 (1814 4650);
PAINT MONO (1814 4650);
FORCEPROP 2 LAST PATH I72
J 0
(1825 4700);
DISPLAY 1.021277 (1825 4700);
PAINT ORANGE (1825 4700);
DISPLAY INVISIBLE (1825 4700);
FORCEPROP 2 LAST CDS_LIB mstr_standard
J 0
(1625 4650);
PAINT ORANGE (1625 4650);
DISPLAY INVISIBLE (1625 4650);
FORCEPROP 1 LAST OFFPAGE TRUE
J 0
(1950 4525);
DISPLAY 0.872340 (1950 4525);
PAINT GREEN (1950 4525);
DISPLAY INVISIBLE (1950 4525);
FORCEPROP 1 LAST COMMENT_BODY TRUE
J 0
(1580 4555);
DISPLAY 0.872340 (1580 4555);
PAINT GREEN (1580 4555);
DISPLAY INVISIBLE (1580 4555);
FORCEADD OFFPAGE..4
(1600 4050);
FORCEPROP 2 LAST $XR0 189 
J 0
(1786 4050);
DISPLAY 0.638298 (1786 4050);
PAINT MONO (1786 4050);
FORCEPROP 2 LAST PATH I73
J 0
(1800 4100);
DISPLAY 1.021277 (1800 4100);
PAINT ORANGE (1800 4100);
DISPLAY INVISIBLE (1800 4100);
FORCEPROP 2 LAST CDS_LIB mstr_standard
J 0
(1600 4050);
PAINT ORANGE (1600 4050);
DISPLAY INVISIBLE (1600 4050);
FORCEPROP 1 LAST OFFPAGE TRUE
J 0
(1925 3925);
DISPLAY 0.872340 (1925 3925);
PAINT GREEN (1925 3925);
DISPLAY INVISIBLE (1925 3925);
FORCEPROP 1 LAST COMMENT_BODY TRUE
J 0
(1575 3950);
DISPLAY 0.872340 (1575 3950);
PAINT GREEN (1575 3950);
DISPLAY INVISIBLE (1575 3950);
FORCEADD OFFPAGE..2
(1625 4250);
FORCEPROP 2 LAST $XR0 189 
J 0
(1814 4250);
DISPLAY 0.638298 (1814 4250);
PAINT MONO (1814 4250);
FORCEPROP 2 LAST PATH I74
J 0
(1825 4300);
DISPLAY 1.021277 (1825 4300);
PAINT ORANGE (1825 4300);
DISPLAY INVISIBLE (1825 4300);
FORCEPROP 2 LAST CDS_LIB mstr_standard
J 0
(1625 4250);
PAINT ORANGE (1625 4250);
DISPLAY INVISIBLE (1625 4250);
FORCEPROP 1 LAST OFFPAGE TRUE
J 0
(1950 4125);
DISPLAY 0.872340 (1950 4125);
PAINT GREEN (1950 4125);
DISPLAY INVISIBLE (1950 4125);
FORCEPROP 1 LAST COMMENT_BODY TRUE
J 0
(1580 4155);
DISPLAY 0.872340 (1580 4155);
PAINT GREEN (1580 4155);
DISPLAY INVISIBLE (1580 4155);
FORCEADD OFFPAGE..2
(1625 4450);
FORCEPROP 2 LAST $XR0 189 
J 0
(1814 4450);
DISPLAY 0.638298 (1814 4450);
PAINT MONO (1814 4450);
FORCEPROP 2 LAST PATH I75
J 0
(1825 4500);
DISPLAY 1.021277 (1825 4500);
PAINT ORANGE (1825 4500);
DISPLAY INVISIBLE (1825 4500);
FORCEPROP 2 LAST CDS_LIB mstr_standard
J 0
(1625 4450);
PAINT ORANGE (1625 4450);
DISPLAY INVISIBLE (1625 4450);
FORCEPROP 1 LAST OFFPAGE TRUE
J 0
(1950 4325);
DISPLAY 0.872340 (1950 4325);
PAINT GREEN (1950 4325);
DISPLAY INVISIBLE (1950 4325);
FORCEPROP 1 LAST COMMENT_BODY TRUE
J 0
(1580 4355);
DISPLAY 0.872340 (1580 4355);
PAINT GREEN (1580 4355);
DISPLAY INVISIBLE (1580 4355);
FORCEADD RES..1
(-100 3800);
FORCEPROP 1 LAST LOCATION R7G114
J 0
(-150 3850);
DISPLAY 0.617021 (-150 3850);
PAINT AQUA (-150 3850);
FORCEPROP 1 LAST MATERIAL CHIP
J 0
(-125 3750);
DISPLAY 0.617021 (-125 3750);
PAINT SKYBLUE (-125 3750);
FORCEPROP 1 LAST VALUE 0.0
J 2
(-275 3800);
DISPLAY 0.617021 (-275 3800);
PAINT SKYBLUE (-275 3800);
FORCEPROP 1 LAST TOLERANCE 5%
J 0
(-250 3800);
DISPLAY 0.617021 (-250 3800);
PAINT SKYBLUE (-250 3800);
FORCEPROP 1 LAST WATTAGE 1/16W
J 2
(-150 3750);
DISPLAY 0.617021 (-150 3750);
PAINT SKYBLUE (-150 3750);
FORCEPROP 1 LAST PART_NUMBER G21497-005
J 0
(-225 3875);
DISPLAY 0.617021 (-225 3875);
PAINT BLUE (-225 3875);
FORCEPROP 1 LAST PACK_TYPE 0402
J 0
(-25 3750);
DISPLAY 0.617021 (-25 3750);
PAINT SKYBLUE (-25 3750);
FORCEPROP 1 LASTPIN (0 3800) $PN 2
J 0
(-38 3812);
DISPLAY 0.787234 (-38 3812);
PAINT ORANGE (-38 3812);
DISPLAY INVISIBLE (-38 3812);
FORCEPROP 1 LASTPIN (-200 3800) $PN 1
J 0
(-188 3812);
DISPLAY 0.787234 (-188 3812);
PAINT ORANGE (-188 3812);
DISPLAY INVISIBLE (-188 3812);
FORCEPROP 2 LAST CDS_LIB mstr_discrete
J 0
(-100 3800);
DISPLAY INVISIBLE (-100 3800);
FORCEPROP 1 LAST PATH I76
J 0
(-150 3950);
DISPLAY 0.978723 (-150 3950);
PAINT WHITE (-150 3950);
DISPLAY INVISIBLE (-150 3950);
FORCEPROP 2 LAST BOM_COST DEBUG
J 0
(-150 3950);
DISPLAY 1.021277 (-150 3950);
PAINT ORANGE (-150 3950);
DISPLAY INVISIBLE (-150 3950);
FORCEPROP 2 LAST ROOM BMC_DEBUG_HEADER
J 0
(-150 3900);
DISPLAY 1.021277 (-150 3900);
PAINT ORANGE (-150 3900);
DISPLAY INVISIBLE (-150 3900);
FORCEADD RES..1
(-50 1800);
FORCEPROP 1 LAST MATERIAL CHIP
J 0
(-150 1550);
DISPLAY 0.617021 (-150 1550);
PAINT SKYBLUE (-150 1550);
FORCEPROP 1 LASTPIN (50 1800) $PN 2
J 0
(12 1812);
DISPLAY 0.617021 (12 1812);
PAINT ORANGE (12 1812);
FORCEPROP 1 LASTPIN (-150 1800) $PN 1
J 0
(-138 1812);
DISPLAY 0.617021 (-138 1812);
PAINT ORANGE (-138 1812);
FORCEPROP 1 LAST PACK_TYPE 0402
J 0
(-150 1450);
DISPLAY 0.617021 (-150 1450);
PAINT SKYBLUE (-150 1450);
FORCEPROP 1 LAST PART_NUMBER G21497-005
J 0
(-150 1500);
DISPLAY 0.617021 (-150 1500);
PAINT BLUE (-150 1500);
FORCEPROP 1 LAST TOLERANCE 5%
J 0
(-150 1650);
DISPLAY 0.617021 (-150 1650);
PAINT SKYBLUE (-150 1650);
FORCEPROP 1 LAST WATTAGE 1/16W
J 0
(-150 1600);
DISPLAY 0.617021 (-150 1600);
PAINT SKYBLUE (-150 1600);
FORCEPROP 1 LAST VALUE 0.0
J 0
(-150 1700);
DISPLAY 0.617021 (-150 1700);
PAINT SKYBLUE (-150 1700);
FORCEPROP 1 LAST LOCATION R25W186
J 0
(-150 1750);
DISPLAY 0.617021 (-150 1750);
PAINT AQUA (-150 1750);
FORCEPROP 1 LAST PATH I77
J 0
(-100 1950);
DISPLAY 0.978723 (-100 1950);
PAINT WHITE (-100 1950);
DISPLAY INVISIBLE (-100 1950);
FORCEPROP 2 LAST CDS_LIB mstr_discrete
J 0
(-50 1800);
PAINT ORANGE (-50 1800);
DISPLAY INVISIBLE (-50 1800);
FORCEPROP 2 LAST SEC_TYPE 0402
J 0
(-100 2000);
DISPLAY 1.021277 (-100 2000);
PAINT ORANGE (-100 2000);
DISPLAY INVISIBLE (-100 2000);
FORCEPROP 2 LAST BOM_COST DEBUG
J 0
(-100 1950);
DISPLAY 1.021277 (-100 1950);
PAINT ORANGE (-100 1950);
DISPLAY INVISIBLE (-100 1950);
FORCEPROP 2 LAST SEC 1
J 0
(-100 2000);
DISPLAY 0.680851 (-100 2000);
PAINT MONO (-100 2000);
DISPLAY INVISIBLE (-100 2000);
FORCEPROP 2 LAST ROOM BMC_DEBUG_HEADER
J 0
(-100 1900);
DISPLAY 1.021277 (-100 1900);
PAINT ORANGE (-100 1900);
DISPLAY INVISIBLE (-100 1900);
FORCEPROP 2 LAST CDS_LOCATION R25W186
J 0
(-100 1850);
DISPLAY 0.617021 (-100 1850);
PAINT AQUA (-100 1850);
DISPLAY INVISIBLE (-100 1850);
FORCEADD OFFPAGE..1
(-650 1800);
FORCEPROP 2 LAST $XR3 255 
J 0
(-1022 1764);
DISPLAY 0.638298 (-1022 1764);
PAINT MONO (-1022 1764);
FORCEPROP 2 LAST $XR2 254 
J 0
(-902 1764);
DISPLAY 0.638298 (-902 1764);
PAINT MONO (-902 1764);
FORCEPROP 2 LAST $XR1 189 
J 0
(-1022 1800);
DISPLAY 0.638298 (-1022 1800);
PAINT MONO (-1022 1800);
FORCEPROP 2 LAST $XR0 148 
J 0
(-902 1800);
DISPLAY 0.638298 (-902 1800);
PAINT MONO (-902 1800);
FORCEPROP 1 LAST COMMENT_BODY TRUE
J 0
(-525 1700);
DISPLAY 0.872340 (-525 1700);
PAINT GREEN (-525 1700);
DISPLAY INVISIBLE (-525 1700);
FORCEPROP 1 LAST OFFPAGE TRUE
J 0
(-325 1675);
DISPLAY 0.872340 (-325 1675);
PAINT GREEN (-325 1675);
DISPLAY INVISIBLE (-325 1675);
FORCEPROP 2 LAST CDS_LIB mstr_standard
J 0
(-650 1800);
PAINT ORANGE (-650 1800);
DISPLAY INVISIBLE (-650 1800);
FORCEPROP 2 LAST PATH I78
J 0
(-900 1850);
DISPLAY 1.021277 (-900 1850);
PAINT ORANGE (-900 1850);
DISPLAY INVISIBLE (-900 1850);
FORCEADD OFFPAGE..1
(-750 4350);
FORCEPROP 2 LAST $XR0 245 
J 0
(-1482 4350);
DISPLAY 0.638298 (-1482 4350);
PAINT MONO (-1482 4350);
FORCEPROP 2 LAST PATH I79
J 0
(-1200 4400);
DISPLAY 1.021277 (-1200 4400);
PAINT ORANGE (-1200 4400);
DISPLAY INVISIBLE (-1200 4400);
FORCEPROP 1 LAST COMMENT_BODY TRUE
J 0
(-625 4250);
DISPLAY 0.872340 (-625 4250);
PAINT GREEN (-625 4250);
DISPLAY INVISIBLE (-625 4250);
FORCEPROP 1 LAST OFFPAGE TRUE
J 0
(-425 4225);
DISPLAY 0.872340 (-425 4225);
PAINT GREEN (-425 4225);
DISPLAY INVISIBLE (-425 4225);
FORCEPROP 2 LAST CDS_LIB mstr_standard
J 0
(-750 4350);
PAINT ORANGE (-750 4350);
DISPLAY INVISIBLE (-750 4350);
FORCEADD RES..1
(-2100 4400);
FORCEPROP 1 LAST PART_NUMBER G21497-005
J 0
(-1950 4400);
DISPLAY 0.617021 (-1950 4400);
PAINT BLUE (-1950 4400);
FORCEPROP 1 LAST LOCATION R7G19
J 0
(-2150 4450);
DISPLAY 0.617021 (-2150 4450);
PAINT AQUA (-2150 4450);
FORCEPROP 1 LAST PACK_TYPE 0402
J 0
(-2000 4350);
DISPLAY 0.617021 (-2000 4350);
PAINT SKYBLUE (-2000 4350);
FORCEPROP 1 LASTPIN (-2000 4400) $PN 2
J 0
(-2038 4412);
DISPLAY 0.617021 (-2038 4412);
PAINT ORANGE (-2038 4412);
FORCEPROP 1 LAST MATERIAL EMPTY
J 0
(-2150 4350);
DISPLAY 0.617021 (-2150 4350);
PAINT RED (-2150 4350);
FORCEPROP 1 LASTPIN (-2200 4400) $PN 1
J 0
(-2188 4412);
DISPLAY 0.617021 (-2188 4412);
PAINT ORANGE (-2188 4412);
FORCEPROP 1 LAST TOLERANCE 5%
J 0
(-2250 4400);
DISPLAY 0.617021 (-2250 4400);
PAINT SKYBLUE (-2250 4400);
FORCEPROP 1 LAST WATTAGE 1/16W
J 2
(-2175 4350);
DISPLAY 0.617021 (-2175 4350);
PAINT SKYBLUE (-2175 4350);
FORCEPROP 1 LAST VALUE 0.0
J 2
(-2275 4400);
DISPLAY 0.617021 (-2275 4400);
PAINT SKYBLUE (-2275 4400);
FORCEPROP 2 LAST SEC_TYPE 0402
J 0
(-2150 4600);
DISPLAY 1.021277 (-2150 4600);
PAINT ORANGE (-2150 4600);
DISPLAY INVISIBLE (-2150 4600);
FORCEPROP 2 LAST SEC 1
J 0
(-2150 4600);
DISPLAY 0.680851 (-2150 4600);
PAINT MONO (-2150 4600);
DISPLAY INVISIBLE (-2150 4600);
FORCEPROP 2 LAST BOM_COST DEBUG
J 0
(-2150 4550);
DISPLAY 1.021277 (-2150 4550);
PAINT ORANGE (-2150 4550);
DISPLAY INVISIBLE (-2150 4550);
FORCEPROP 1 LAST PATH I8
J 0
(-2150 4550);
DISPLAY 0.978723 (-2150 4550);
PAINT WHITE (-2150 4550);
DISPLAY INVISIBLE (-2150 4550);
FORCEPROP 2 LAST ROOM BMC_DEBUG_HEADER
J 0
(-2150 4500);
DISPLAY 1.021277 (-2150 4500);
PAINT ORANGE (-2150 4500);
DISPLAY INVISIBLE (-2150 4500);
FORCEPROP 2 LAST CDS_LOCATION R7G19
J 0
(-2150 4450);
DISPLAY 0.617021 (-2150 4450);
PAINT AQUA (-2150 4450);
DISPLAY INVISIBLE (-2150 4450);
FORCEPROP 2 LAST CDS_LIB mstr_discrete
J 0
(-2100 4400);
PAINT ORANGE (-2100 4400);
DISPLAY INVISIBLE (-2100 4400);
FORCEADD OFFPAGE..1
(-750 4150);
FORCEPROP 2 LAST $XR0 245 
J 0
(-1212 4150);
DISPLAY 0.638298 (-1212 4150);
PAINT MONO (-1212 4150);
FORCEPROP 2 LAST PATH I80
J 0
(-1200 4200);
DISPLAY 1.021277 (-1200 4200);
PAINT ORANGE (-1200 4200);
DISPLAY INVISIBLE (-1200 4200);
FORCEPROP 1 LAST COMMENT_BODY TRUE
J 0
(-625 4050);
DISPLAY 0.872340 (-625 4050);
PAINT GREEN (-625 4050);
DISPLAY INVISIBLE (-625 4050);
FORCEPROP 1 LAST OFFPAGE TRUE
J 0
(-425 4025);
DISPLAY 0.872340 (-425 4025);
PAINT GREEN (-425 4025);
DISPLAY INVISIBLE (-425 4025);
FORCEPROP 2 LAST CDS_LIB mstr_standard
J 0
(-750 4150);
PAINT ORANGE (-750 4150);
DISPLAY INVISIBLE (-750 4150);
FORCEADD RES..1
(-2100 4600);
FORCEPROP 1 LAST PART_NUMBER G21497-005
J 0
(-1950 4600);
DISPLAY 0.617021 (-1950 4600);
PAINT BLUE (-1950 4600);
FORCEPROP 1 LAST PACK_TYPE 0402
J 0
(-2000 4550);
DISPLAY 0.617021 (-2000 4550);
PAINT SKYBLUE (-2000 4550);
FORCEPROP 1 LAST LOCATION R8G9
J 0
(-2150 4650);
DISPLAY 0.617021 (-2150 4650);
PAINT AQUA (-2150 4650);
FORCEPROP 1 LASTPIN (-2200 4600) $PN 1
J 0
(-2188 4612);
DISPLAY 0.617021 (-2188 4612);
PAINT ORANGE (-2188 4612);
FORCEPROP 1 LASTPIN (-2000 4600) $PN 2
J 0
(-2038 4612);
DISPLAY 0.617021 (-2038 4612);
PAINT ORANGE (-2038 4612);
FORCEPROP 1 LAST TOLERANCE 5%
J 0
(-2250 4600);
DISPLAY 0.617021 (-2250 4600);
PAINT SKYBLUE (-2250 4600);
FORCEPROP 1 LAST VALUE 0.0
J 2
(-2275 4600);
DISPLAY 0.617021 (-2275 4600);
PAINT SKYBLUE (-2275 4600);
FORCEPROP 1 LAST WATTAGE 1/16W
J 2
(-2175 4550);
DISPLAY 0.617021 (-2175 4550);
PAINT SKYBLUE (-2175 4550);
FORCEPROP 1 LAST MATERIAL EMPTY
J 0
(-2150 4550);
DISPLAY 0.617021 (-2150 4550);
PAINT RED (-2150 4550);
FORCEPROP 1 LAST PATH I9
J 0
(-2150 4750);
DISPLAY 0.978723 (-2150 4750);
PAINT WHITE (-2150 4750);
DISPLAY INVISIBLE (-2150 4750);
FORCEPROP 2 LAST $SEC 1
J 0
(-2150 4800);
PAINT MONO (-2150 4800);
DISPLAY INVISIBLE (-2150 4800);
FORCEPROP 2 LAST CDS_SEC 1
J 0
(-2150 4800);
PAINT MONO (-2150 4800);
DISPLAY INVISIBLE (-2150 4800);
FORCEPROP 2 LAST BOM_COST DEBUG
J 0
(-2150 4750);
DISPLAY 1.021277 (-2150 4750);
PAINT ORANGE (-2150 4750);
DISPLAY INVISIBLE (-2150 4750);
FORCEPROP 2 LAST ROOM BMC_DEBUG_HEADER
J 0
(-2150 4700);
DISPLAY 1.021277 (-2150 4700);
PAINT ORANGE (-2150 4700);
DISPLAY INVISIBLE (-2150 4700);
FORCEPROP 2 LAST CDS_LIB mstr_discrete
J 0
(-2100 4600);
PAINT MONO (-2100 4600);
DISPLAY INVISIBLE (-2100 4600);
FORCEPROP 2 LAST CDS_LOCATION R8G9
J 0
(-2150 4650);
DISPLAY 0.617021 (-2150 4650);
PAINT AQUA (-2150 4650);
DISPLAY INVISIBLE (-2150 4650);
FORCEADD DNS..2
(180 1595);
PAINT RED (180 1595);
FORCEPROP 2 LAST CDS_LIB mstr_misc
J 0
(180 1595);
PAINT ORANGE (180 1595);
DISPLAY INVISIBLE (180 1595);
FORCEPROP 1 LAST COMMENT_BODY TRUE
R 1
J 0
(255 1370);
DISPLAY 0.872340 (255 1370);
PAINT GREEN (255 1370);
DISPLAY INVISIBLE (255 1370);
FORCEADD BOM_NOTE..1
(1225 2725);
FORCEPROP 0 LAST L2 BMC TO CPLD COMMUNICATION
J 0
(1100 2550);
DISPLAY 1.021277 (1100 2550);
PAINT ORANGE (1100 2550);
FORCEPROP 0 LAST L1 UNSTUFF 0-OHM RESISTORS FOR
J 0
(1100 2600);
DISPLAY 1.021277 (1100 2600);
PAINT ORANGE (1100 2600);
FORCEPROP 2 LAST CDS_LIB mstr_symbols
J 0
(1225 2725);
PAINT ORANGE (1225 2725);
DISPLAY INVISIBLE (1225 2725);
FORCEPROP 1 LAST COMMENT_BODY TRUE
J 0
(1250 2825);
DISPLAY 0.978723 (1250 2825);
PAINT ORANGE (1250 2825);
DISPLAY INVISIBLE (1250 2825);
FORCEADD DNS..2
(-2095 4595);
PAINT RED (-2095 4595);
FORCEPROP 2 LAST CDS_LIB mstr_misc
J 0
(-2095 4595);
PAINT ORANGE (-2095 4595);
DISPLAY INVISIBLE (-2095 4595);
FORCEPROP 1 LAST COMMENT_BODY TRUE
R 1
J 0
(-2020 4370);
DISPLAY 0.872340 (-2020 4370);
PAINT GREEN (-2020 4370);
DISPLAY INVISIBLE (-2020 4370);
FORCEADD DNS..2
(-2095 4395);
PAINT RED (-2095 4395);
FORCEPROP 2 LAST CDS_LIB mstr_misc
J 0
(-2095 4395);
PAINT ORANGE (-2095 4395);
DISPLAY INVISIBLE (-2095 4395);
FORCEPROP 1 LAST COMMENT_BODY TRUE
R 1
J 0
(-2020 4170);
DISPLAY 0.872340 (-2020 4170);
PAINT GREEN (-2020 4170);
DISPLAY INVISIBLE (-2020 4170);
FORCEADD DNS..2
(-2095 2245);
PAINT RED (-2095 2245);
FORCEPROP 2 LAST CDS_LIB mstr_misc
J 0
(-2095 2245);
PAINT ORANGE (-2095 2245);
DISPLAY INVISIBLE (-2095 2245);
FORCEPROP 1 LAST COMMENT_BODY TRUE
R 1
J 0
(-2020 2020);
DISPLAY 0.872340 (-2020 2020);
PAINT GREEN (-2020 2020);
DISPLAY INVISIBLE (-2020 2020);
FORCEADD DNS..2
(-2095 3670);
PAINT RED (-2095 3670);
FORCEPROP 2 LAST CDS_LIB mstr_misc
J 0
(-2095 3670);
PAINT ORANGE (-2095 3670);
DISPLAY INVISIBLE (-2095 3670);
FORCEPROP 1 LAST COMMENT_BODY TRUE
R 1
J 0
(-2020 3445);
DISPLAY 0.872340 (-2020 3445);
PAINT GREEN (-2020 3445);
DISPLAY INVISIBLE (-2020 3445);
FORCEADD BOM_NOTE..1
(-3275 1425);
FORCEPROP 0 LAST L1 UNSTUFF CPLD AND BMC RES FOR PCH OR PCH GBE
J 0
(-3400 1300);
DISPLAY 1.021277 (-3400 1300);
PAINT ORANGE (-3400 1300);
FORCEPROP 2 LAST CDS_LIB mstr_symbols
J 0
(-3275 1425);
PAINT ORANGE (-3275 1425);
DISPLAY INVISIBLE (-3275 1425);
FORCEPROP 1 LAST COMMENT_BODY TRUE
J 0
(-3250 1525);
DISPLAY 0.978723 (-3250 1525);
PAINT ORANGE (-3250 1525);
DISPLAY INVISIBLE (-3250 1525);
FORCEADD DESIGN_NOTE..1
(-75 1125);
FORCEPROP 0 LAST L2 CPLD JTAG DISABLED WHEN LOW
J 0
(-275 925);
DISPLAY 1.063830 (-275 925);
PAINT WHITE (-275 925);
FORCEPROP 0 LAST L3 CPLD JTAG ENABLED WHEN HIGH (DEFAULT)
J 0
(-275 1000);
DISPLAY 1.085106 (-275 1000);
PAINT ORANGE (-275 1000);
FORCEPROP 2 LAST ROOM SB
J 0
(-250 1025);
DISPLAY 1.361702 (-250 1025);
PAINT ORANGE (-250 1025);
DISPLAY INVISIBLE (-250 1025);
FORCEPROP 2 LAST CDS_LIB mstr_symbols
J 0
(-75 1125);
PAINT ORANGE (-75 1125);
DISPLAY INVISIBLE (-75 1125);
FORCEPROP 2 LAST BOM_COST SB
J 0
(-250 1025);
DISPLAY 1.361702 (-250 1025);
PAINT ORANGE (-250 1025);
DISPLAY INVISIBLE (-250 1025);
FORCEPROP 1 LAST COMMENT_BODY TRUE
J 0
(-50 1225);
DISPLAY 1.319149 (-50 1225);
PAINT ORANGE (-50 1225);
DISPLAY INVISIBLE (-50 1225);
FORCEADD DNS..2
(-2095 2795);
PAINT RED (-2095 2795);
FORCEPROP 2 LAST CDS_LIB mstr_misc
J 0
(-2095 2795);
PAINT ORANGE (-2095 2795);
DISPLAY INVISIBLE (-2095 2795);
FORCEPROP 1 LAST COMMENT_BODY TRUE
R 1
J 0
(-2020 2570);
DISPLAY 0.872340 (-2020 2570);
PAINT GREEN (-2020 2570);
DISPLAY INVISIBLE (-2020 2570);
FORCEADD DNS..2
(-2095 3495);
PAINT RED (-2095 3495);
FORCEPROP 2 LAST CDS_LIB mstr_misc
J 0
(-2095 3495);
PAINT ORANGE (-2095 3495);
DISPLAY INVISIBLE (-2095 3495);
FORCEPROP 1 LAST COMMENT_BODY TRUE
R 1
J 0
(-2020 3270);
DISPLAY 0.872340 (-2020 3270);
PAINT GREEN (-2020 3270);
DISPLAY INVISIBLE (-2020 3270);
FORCEADD DNS..2
(-2095 2970);
PAINT RED (-2095 2970);
FORCEPROP 2 LAST CDS_LIB mstr_misc
J 0
(-2095 2970);
PAINT ORANGE (-2095 2970);
DISPLAY INVISIBLE (-2095 2970);
FORCEPROP 1 LAST COMMENT_BODY TRUE
R 1
J 0
(-2020 2745);
DISPLAY 0.872340 (-2020 2745);
PAINT GREEN (-2020 2745);
DISPLAY INVISIBLE (-2020 2745);
FORCEADD DNS..2
(-2095 2070);
PAINT RED (-2095 2070);
FORCEPROP 2 LAST CDS_LIB mstr_misc
J 0
(-2095 2070);
PAINT ORANGE (-2095 2070);
DISPLAY INVISIBLE (-2095 2070);
FORCEPROP 1 LAST COMMENT_BODY TRUE
R 1
J 0
(-2020 1845);
DISPLAY 0.872340 (-2020 1845);
PAINT GREEN (-2020 1845);
DISPLAY INVISIBLE (-2020 1845);
FORCEADD DNS..2
(-2095 4220);
PAINT RED (-2095 4220);
FORCEPROP 2 LAST CDS_LIB mstr_misc
J 0
(-2095 4220);
PAINT ORANGE (-2095 4220);
DISPLAY INVISIBLE (-2095 4220);
FORCEPROP 1 LAST COMMENT_BODY TRUE
R 1
J 0
(-2020 3995);
DISPLAY 0.872340 (-2020 3995);
PAINT GREEN (-2020 3995);
DISPLAY INVISIBLE (-2020 3995);
FORCEADD DESIGN_NOTE..1
(2800 4300);
FORCEPROP 0 LAST L2 FROM JTAG DEBUG DEVICES PLUGGED INTO THE BOARD
J 0
(2600 4125);
DISPLAY 0.808511 (2600 4125);
PAINT ORANGE (2600 4125);
FORCEPROP 0 LAST L1 1N5819HW USED TO PREVENT LEAKAGE ONTO P3V3_STBY RAIL
J 0
(2600 4175);
DISPLAY 0.808511 (2600 4175);
PAINT ORANGE (2600 4175);
FORCEPROP 2 LAST CDS_LIB mstr_symbols
J 0
(2800 4300);
PAINT MONO (2800 4300);
DISPLAY INVISIBLE (2800 4300);
FORCEPROP 1 LAST COMMENT_BODY TRUE
J 0
(2825 4400);
DISPLAY 0.978723 (2825 4400);
PAINT ORANGE (2825 4400);
DISPLAY INVISIBLE (2825 4400);
FORCEADD INTEL_CORP_BPAGE..1
(4250 75);
FORCEPROP 1 LAST CDS_CON_LAST_MODIFIED Fri Jun 16 17:49:10 2017
J 0
(2825 400);
PAINT ORANGE (2825 400);
DISPLAY INVISIBLE (2825 400);
FORCEPROP 1 LAST CUSTOM_TXT_CDS <CURRENT_DESIGN_SHEET> OF <TOTAL_DESIGN_SHEETS>
J 0
(3750 100);
PAINT ORANGE (3750 100);
FORCEPROP 1 LAST CUSTOM_TXT_CDS <CON_LAST_MODIFIED>
J 0
(250 175);
PAINT ORANGE (250 175);
FORCEPROP 2 LAST CUSTOM_TXT_CDS <XR_PAGE_TITLE>
J 0
(-3640 5325);
DISPLAY 0.638298 (-3640 5325);
PAINT PINK (-3640 5325);
DISPLAY INVISIBLE (-3640 5325);
FORCEPROP 1 LAST SCH_TITLE BMC JTAG HEADER
J 0
(-3700 125);
DISPLAY 1.212766 (-3700 125);
PAINT ORANGE (-3700 125);
FORCEPROP 2 LAST PAGE_BORDER TRUE
J 0
(-3640 5325);
DISPLAY 0.638298 (-3640 5325);
PAINT PINK (-3640 5325);
DISPLAY INVISIBLE (-3640 5325);
FORCEPROP 2 LAST CDS_LIB mstr_symbols
J 0
(4250 75);
PAINT MONO (4250 75);
DISPLAY INVISIBLE (4250 75);
FORCEPROP 1 LAST COMMENT_BODY TRUE
J 0
(4262 87);
DISPLAY 0.468085 (4262 87);
PAINT GREEN (4262 87);
DISPLAY INVISIBLE (4262 87);
FORCEPROP 2 LAST CDS_XR_PAGE_TITLE CR-189 : @BASEBOARD_FAB2_LIB.BASEBOARD_FAB2(SCH_1):PAGE189
J 0
(-3640 5325);
DISPLAY 0.638298 (-3640 5325);
PAINT PINK (-3640 5325);
DISPLAY INVISIBLE (-3640 5325);
WIRE 16 -1 (175 2150)(175 2100);
WIRE 16 -1 (175 1500)(175 1450);
WIRE 16 -1 (3375 3800)(3375 3525);
WIRE 16 -1 (3375 3525)(3400 3525);
WIRE 16 -1 (2600 3650)(2600 3825);
WIRE 16 -1 (2900 3650)(2600 3650);
WIRE 16 -1 (2600 3600)(2600 3650);
WIRE 16 -1 (2900 3650)(3200 3650);
WIRE 16 -1 (2900 3600)(2900 3650);
WIRE 16 -1 (3200 3650)(3200 3600);
WIRE 16 -1 (3675 2975)(3675 2850);
WIRE 16 -1 (3800 2975)(3675 2975);
WIRE 16 -1 (3200 2600)(3200 2525);
WIRE 16 -1 (775 3650)(775 3625);
WIRE 16 -1 (775 3425)(775 3400);
WIRE 3 682 (-975 4950)(1975 4950);
WIRE 3 682 (1975 3300)(1975 4950);
WIRE 3 682 (-1000 3300)(-1000 4950);
WIRE 3 682 (-1000 3300)(1975 3300);
WIRE 16 -1 (1000 4450)(1575 4450);
FORCEPROP 2 LAST SIG_NAME JTAG_TMS
J 1
(1250 4460);
DISPLAY 0.617021 (1250 4460);
PAINT ORANGE (1250 4460);
WIRE 16 -1 (400 3800)(0 3800);
FORCEPROP 2 LAST SIG_NAME BMC_JTAG_SEL_N_MUX
J 0
(15 3810);
DISPLAY 0.638298 (15 3810);
PAINT ORANGE (15 3810);
FORCEPROP 2 LASTPROP $XRERR UNIQUE?
J 0
(-225 3810);
DISPLAY 0.638298 (-225 3810);
PAINT MONO (-225 3810);
DISPLAY INVISIBLE (-225 3810);
WIRE 16 -1 (600 4550)(400 4550);
WIRE 16 -1 (400 4550)(400 4350);
WIRE 16 -1 (600 4350)(400 4350);
WIRE 16 -1 (400 3800)(400 3950);
WIRE 16 -1 (400 3950)(600 3950);
WIRE 16 -1 (400 4150)(400 3950);
WIRE 16 -1 (400 4350)(400 4150);
WIRE 16 -1 (600 4150)(400 4150);
WIRE 3 682 (-1050 1900)(-1050 1400);
WIRE 3 682 (100 1900)(-1050 1900);
WIRE 3 682 (-1050 1400)(100 1400);
WIRE 3 682 (100 1400)(100 1900);
WIRE 16 -1 (100 4150)(-700 4150);
WIRE 16 -1 (-25 4250)(100 4250);
FORCEPROP 2 LAST SIG_NAME JTAG_PLD_TCK_MUX
J 0
(-685 4160);
DISPLAY 0.617021 (-685 4160);
PAINT ORANGE (-685 4160);
WIRE 16 -1 (100 4250)(100 4150);
WIRE 16 -1 (100 4250)(600 4250);
WIRE 16 -1 (1000 4650)(1575 4650);
FORCEPROP 0 LAST SIG_NAME JTAG_TDI
J 1
(1250 4660);
DISPLAY 0.617021 (1250 4660);
PAINT ORANGE (1250 4660);
WIRE 16 -1 (-2000 4400)(-1675 4400);
WIRE 16 -1 (-1675 4400)(-1425 4400);
FORCEPROP 0 LAST SIG_NAME JTAG_TDI
J 1
(-1525 4410);
DISPLAY 0.617021 (-1525 4410);
PAINT ORANGE (-1525 4410);
WIRE 16 -1 (-2000 4225)(-1675 4225);
WIRE 16 -1 (-1675 4400)(-1675 4225);
WIRE 16 -1 (-1675 4225)(-1675 4050);
WIRE 16 -1 (-2000 4050)(-1675 4050);
WIRE 16 682 (-3700 1225)(-1100 1225);
WIRE 16 682 (-3700 4950)(-3700 1225);
WIRE 16 682 (-1100 1225)(-1100 4950);
WIRE 16 682 (-1100 4950)(-3700 4950);
WIRE 16 -1 (-225 4050)(-700 4050);
FORCEPROP 2 LAST SIG_NAME JTAG_PLD_TDO_MUX_R
J 0
(-710 4060);
DISPLAY 0.617021 (-710 4060);
PAINT ORANGE (-710 4060);
WIRE 16 -1 (-200 3800)(-650 3800);
FORCEPROP 2 LAST SIG_NAME BMC_JTAG_SEL_N
J 0
(-660 3810);
DISPLAY 0.638298 (-660 3810);
PAINT ORANGE (-660 3810);
WIRE 16 -1 (-25 4050)(600 4050);
FORCEPROP 2 LAST SIG_NAME JTAG_PLD_TDO_MUX
J 0
(40 4060);
DISPLAY 0.617021 (40 4060);
PAINT ORANGE (40 4060);
FORCEPROP 2 LASTPROP $XRERR UNIQUE?
J 0
(-200 4060);
DISPLAY 0.638298 (-200 4060);
PAINT MONO (-200 4060);
DISPLAY INVISIBLE (-200 4060);
WIRE 16 -1 (-25 4450)(100 4450);
FORCEPROP 2 LAST SIG_NAME JTAG_PLD_TMS_MUX
J 0
(-685 4360);
DISPLAY 0.617021 (-685 4360);
PAINT ORANGE (-685 4360);
WIRE 16 -1 (100 4450)(600 4450);
WIRE 16 -1 (100 4350)(100 4450);
WIRE 16 -1 (-700 4350)(100 4350);
WIRE 16 -1 (-225 4250)(-700 4250);
FORCEPROP 2 LAST SIG_NAME JTAG_PLD_TCK
J 0
(-685 4260);
DISPLAY 0.617021 (-685 4260);
PAINT ORANGE (-685 4260);
WIRE 16 -1 (-225 4450)(-700 4450);
FORCEPROP 2 LAST SIG_NAME JTAG_PLD_TMS
J 0
(-685 4460);
DISPLAY 0.617021 (-685 4460);
PAINT ORANGE (-685 4460);
WIRE 16 -1 (3200 2800)(3200 2925);
WIRE 16 -1 (3800 2925)(3200 2925);
WIRE 16 -1 (2950 2925)(3200 2925);
FORCEPROP 2 LAST SIG_NAME JTAG_TCK_R
J 0
(3290 2935);
DISPLAY 0.617021 (3290 2935);
PAINT ORANGE (3290 2935);
FORCEPROP 2 LASTPROP $XRERR UNIQUE?
J 0
(3050 2935);
DISPLAY 0.638298 (3050 2935);
PAINT MONO (3050 2935);
DISPLAY INVISIBLE (3050 2935);
WIRE 16 -1 (3800 3125)(1450 3125);
FORCEPROP 2 LAST SIG_NAME JTAG_TRST_N
J 0
(1465 3135);
DISPLAY 0.617021 (1465 3135);
PAINT ORANGE (1465 3135);
WIRE 16 -1 (-600 1800)(-150 1800);
FORCEPROP 2 LAST SIG_NAME BMC_JTAG_SEL_N
J 0
(-560 1810);
DISPLAY 0.638298 (-560 1810);
PAINT ORANGE (-560 1810);
WIRE 16 -1 (175 1800)(175 1700);
WIRE 16 -1 (175 1800)(50 1800);
WIRE 16 -1 (175 1800)(950 1800);
WIRE 16 -1 (175 1900)(175 1800);
WIRE 16 -1 (-2200 2625)(-2800 2625);
FORCEPROP 0 LAST SIG_NAME JTAG_BMC_TCK
J 0
(-2785 2635);
DISPLAY 0.617021 (-2785 2635);
PAINT ORANGE (-2785 2635);
WIRE 16 -1 (-2000 1900)(-1675 1900);
WIRE 16 -1 (-1675 2075)(-1675 1900);
WIRE 16 -1 (-2000 2075)(-1675 2075);
WIRE 16 -1 (-2000 2250)(-1675 2250);
WIRE 16 -1 (-1675 2250)(-1675 2075);
WIRE 16 -1 (-1675 2250)(-1425 2250);
FORCEPROP 2 LAST SIG_NAME JTAG_TDO
J 1
(-1525 2260);
DISPLAY 0.617021 (-1525 2260);
PAINT ORANGE (-1525 2260);
WIRE 16 -1 (1000 4250)(1575 4250);
FORCEPROP 0 LAST SIG_NAME JTAG_TCK
J 1
(1250 4260);
DISPLAY 0.617021 (1250 4260);
PAINT ORANGE (1250 4260);
WIRE 16 -1 (1000 4050)(1550 4050);
FORCEPROP 2 LAST SIG_NAME JTAG_TDO
J 1
(1275 4060);
DISPLAY 0.617021 (1275 4060);
PAINT ORANGE (1275 4060);
WIRE 16 -1 (-2000 3350)(-1675 3350);
WIRE 16 -1 (-2000 3500)(-1675 3500);
WIRE 16 -1 (-1675 3500)(-1675 3350);
WIRE 16 -1 (-1675 3675)(-1675 3500);
WIRE 16 -1 (-2000 3675)(-1675 3675);
WIRE 16 -1 (-1675 3675)(-1425 3675);
FORCEPROP 2 LAST SIG_NAME JTAG_TMS
J 1
(-1525 3685);
DISPLAY 0.617021 (-1525 3685);
PAINT ORANGE (-1525 3685);
WIRE 16 -1 (-2000 2625)(-1675 2625);
WIRE 16 -1 (-2000 2800)(-1675 2800);
WIRE 16 -1 (-1675 2800)(-1675 2625);
WIRE 16 -1 (-1675 2975)(-1675 2800);
WIRE 16 -1 (-1675 2975)(-1425 2975);
FORCEPROP 0 LAST SIG_NAME JTAG_TCK
J 1
(-1525 2985);
DISPLAY 0.617021 (-1525 2985);
PAINT ORANGE (-1525 2985);
WIRE 16 -1 (-2000 2975)(-1675 2975);
WIRE 16 -1 (3650 3525)(3600 3525);
WIRE 16 -1 (3650 3275)(3650 3525);
FORCEPROP 0 LAST VOLTAGE 3.3
J 0
(3650 3425);
DISPLAY 1.021277 (3650 3425);
PAINT SKYBLUE (3650 3425);
DISPLAY INVISIBLE (3650 3425);
WIRE 16 -1 (3800 3275)(3650 3275);
FORCEPROP 2 LAST SIG_NAME P3V3_STBY_PLD_D
J 0
(3440 3585);
DISPLAY 0.617021 (3440 3585);
PAINT ORANGE (3440 3585);
FORCEPROP 2 LASTPROP $XRERR UNIQUE?
J 0
(3200 3585);
DISPLAY 0.638298 (3200 3585);
PAINT MONO (3200 3585);
DISPLAY INVISIBLE (3200 3585);
WIRE 16 -1 (3200 3025)(3800 3025);
WIRE 16 -1 (3200 3400)(3200 3025);
WIRE 16 -1 (2625 3025)(3200 3025);
FORCEPROP 2 LAST SIG_NAME JTAG_TMS_R
J 0
(3290 3035);
DISPLAY 0.617021 (3290 3035);
PAINT ORANGE (3290 3035);
FORCEPROP 2 LASTPROP $XRERR UNIQUE?
J 0
(3050 3035);
DISPLAY 0.638298 (3050 3035);
PAINT MONO (3050 3035);
DISPLAY INVISIBLE (3050 3035);
WIRE 16 -1 (2150 3225)(2600 3225);
WIRE 16 -1 (2600 3400)(2600 3225);
WIRE 16 -1 (3800 3225)(2600 3225);
FORCEPROP 2 LAST SIG_NAME JTAG_TDO_R
J 0
(3265 3235);
DISPLAY 0.617021 (3265 3235);
PAINT ORANGE (3265 3235);
FORCEPROP 2 LASTPROP $XRERR UNIQUE?
J 0
(3025 3235);
DISPLAY 0.638298 (3025 3235);
PAINT MONO (3025 3235);
DISPLAY INVISIBLE (3025 3235);
WIRE 16 -1 (2525 3175)(2900 3175);
WIRE 16 -1 (2900 3400)(2900 3175);
WIRE 16 -1 (3800 3175)(2900 3175);
FORCEPROP 2 LAST SIG_NAME JTAG_TDI_R
J 0
(3265 3185);
DISPLAY 0.617021 (3265 3185);
PAINT ORANGE (3265 3185);
FORCEPROP 2 LASTPROP $XRERR UNIQUE?
J 0
(3025 3185);
DISPLAY 0.638298 (3025 3185);
PAINT MONO (3025 3185);
DISPLAY INVISIBLE (3025 3185);
WIRE 16 -1 (-2200 3500)(-2800 3500);
FORCEPROP 0 LAST SIG_NAME JTAG_PCH_PLD_TMS
J 0
(-2785 3510);
DISPLAY 0.617021 (-2785 3510);
PAINT ORANGE (-2785 3510);
WIRE 16 -1 (-2200 2975)(-2800 2975);
FORCEPROP 0 LAST SIG_NAME JTAG_PCH_GBE_CLK
J 0
(-2785 2985);
DISPLAY 0.617021 (-2785 2985);
PAINT ORANGE (-2785 2985);
WIRE 16 -1 (-2200 1900)(-2800 1900);
FORCEPROP 2 LAST SIG_NAME JTAG_BMC_TDO
J 0
(-2785 1910);
DISPLAY 0.617021 (-2785 1910);
PAINT ORANGE (-2785 1910);
WIRE 16 -1 (-2200 2075)(-2800 2075);
FORCEPROP 0 LAST SIG_NAME JTAG_PCH_PLD_TDO
J 0
(-2785 2085);
DISPLAY 0.617021 (-2785 2085);
PAINT ORANGE (-2785 2085);
WIRE 16 -1 (-2200 2250)(-2800 2250);
FORCEPROP 2 LAST SIG_NAME JTAG_PCH_GBE_TDO
J 0
(-2785 2260);
DISPLAY 0.617021 (-2785 2260);
PAINT ORANGE (-2785 2260);
WIRE 16 -1 (-2200 2800)(-2800 2800);
FORCEPROP 0 LAST SIG_NAME JTAG_PCH_PLD_TCK
J 0
(-2785 2810);
DISPLAY 0.617021 (-2785 2810);
PAINT ORANGE (-2785 2810);
WIRE 16 -1 (-2200 3350)(-2800 3350);
FORCEPROP 2 LAST SIG_NAME JTAG_BMC_TMS
J 0
(-2785 3360);
DISPLAY 0.617021 (-2785 3360);
PAINT ORANGE (-2785 3360);
WIRE 16 -1 (-2200 3675)(-2800 3675);
FORCEPROP 2 LAST SIG_NAME JTAG_PCH_GBE_TMS
J 0
(-2785 3685);
DISPLAY 0.617021 (-2785 3685);
PAINT ORANGE (-2785 3685);
WIRE 16 -1 (-2200 4050)(-2800 4050);
FORCEPROP 2 LAST SIG_NAME JTAG_BMC_TDI
J 0
(-2785 4060);
DISPLAY 0.617021 (-2785 4060);
PAINT ORANGE (-2785 4060);
WIRE 16 -1 (-2200 4225)(-2800 4225);
FORCEPROP 0 LAST SIG_NAME JTAG_PCH_PLD_TDI
J 0
(-2785 4235);
DISPLAY 0.617021 (-2785 4235);
PAINT ORANGE (-2785 4235);
WIRE 16 -1 (-2200 4400)(-2800 4400);
FORCEPROP 2 LAST SIG_NAME JTAG_PCH_GBE_TDI
J 0
(-2785 4410);
DISPLAY 0.617021 (-2785 4410);
PAINT ORANGE (-2785 4410);
WIRE 16 -1 (-2200 4775)(-2800 4775);
FORCEPROP 2 LAST SIG_NAME JTAG_BMC_TRST_N
J 0
(-2785 4785);
DISPLAY 0.617021 (-2785 4785);
PAINT ORANGE (-2785 4785);
WIRE 16 -1 (-2200 4600)(-2800 4600);
FORCEPROP 2 LAST SIG_NAME JTAG_PCH_GBE_TRST_N
J 0
(-2785 4610);
DISPLAY 0.617021 (-2785 4610);
PAINT ORANGE (-2785 4610);
WIRE 16 -1 (-2000 4600)(-1675 4600);
WIRE 16 -1 (-1675 4600)(-1675 4775);
WIRE 16 -1 (-1675 4775)(-1425 4775);
FORCEPROP 0 LAST SIG_NAME JTAG_TRST_N
J 1
(-1525 4785);
DISPLAY 0.617021 (-1525 4785);
PAINT ORANGE (-1525 4785);
WIRE 16 -1 (-2000 4775)(-1675 4775);
WIRE 16 -1 (1450 3225)(1950 3225);
FORCEPROP 2 LAST SIG_NAME JTAG_TDO
J 0
(1465 3235);
DISPLAY 0.617021 (1465 3235);
PAINT ORANGE (1465 3235);
WIRE 16 -1 (1450 3175)(2325 3175);
FORCEPROP 2 LAST SIG_NAME JTAG_TDI
J 0
(1465 3185);
DISPLAY 0.617021 (1465 3185);
PAINT ORANGE (1465 3185);
WIRE 16 -1 (1450 3025)(2425 3025);
FORCEPROP 2 LAST SIG_NAME JTAG_TMS
J 0
(1465 3035);
DISPLAY 0.617021 (1465 3035);
PAINT ORANGE (1465 3035);
WIRE 16 -1 (1450 2925)(2750 2925);
FORCEPROP 2 LAST SIG_NAME JTAG_TCK
J 0
(1465 2935);
DISPLAY 0.617021 (1465 2935);
PAINT ORANGE (1465 2935);
WIRE 16 -1 (3800 3075)(1450 3075);
FORCEPROP 2 LAST SIG_NAME PWRGD_P3V3_STBY
J 0
(1465 3085);
DISPLAY 0.617021 (1465 3085);
PAINT ORANGE (1465 3085);
WIRE 16 -1 (-225 4650)(-700 4650);
FORCEPROP 0 LAST SIG_NAME JTAG_PLD_TDI
J 0
(-685 4660);
DISPLAY 0.617021 (-685 4660);
PAINT ORANGE (-685 4660);
WIRE 16 -1 (-25 4650)(600 4650);
FORCEPROP 0 LAST SIG_NAME JTAG_PLD_TDI_MUX
J 0
(40 4660);
DISPLAY 0.617021 (40 4660);
PAINT ORANGE (40 4660);
FORCEPROP 2 LASTPROP $XRERR UNIQUE?
J 0
(-200 4660);
DISPLAY 0.638298 (-200 4660);
PAINT MONO (-200 4660);
DISPLAY INVISIBLE (-200 4660);
DOT 1 (100 4250);
DOT 1 (400 4350);
DOT 1 (100 4450);
DOT 1 (175 1800);
DOT 1 (-1675 4775);
DOT 1 (-1675 4225);
DOT 1 (-1675 4400);
DOT 1 (-1675 3675);
DOT 1 (-1675 3500);
DOT 1 (-1675 2800);
DOT 1 (-1675 2975);
DOT 1 (-1675 2250);
DOT 1 (-1675 2075);
DOT 1 (2900 3650);
DOT 1 (3200 3025);
DOT 1 (3200 2925);
DOT 1 (2900 3175);
DOT 1 (2600 3225);
DOT 1 (2600 3650);
DOT 1 (400 4150);
DOT 1 (400 3950);
FORCENOTE
TP FAB3 ADD RES 1014
(-1050 1350) 0;
DISPLAY LEFT (-1050 1350);
DISPLAY 0.638298 (-1050 1350);
PAINT RED (-1050 1350);
FORCENOTE
ROOM=BMC_DEBUG_HEADER
(-3375 350) 0;
DISPLAY LEFT (-3375 350);
DISPLAY 1.021277 (-3375 350);
PAINT PURPLE (-3375 350);
FORCENOTE
PCH GBE
(-3575 3125) 0;
DISPLAY LEFT (-3575 3125);
DISPLAY 1.021277 (-3575 3125);
PAINT PURPLE (-3575 3125);
FORCENOTE
PCH PLD
(-3575 3025) 0;
DISPLAY LEFT (-3575 3025);
DISPLAY 1.021277 (-3575 3025);
PAINT PURPLE (-3575 3025);
FORCENOTE
CPLD
(-3525 2825) 0;
DISPLAY LEFT (-3525 2825);
DISPLAY 1.021277 (-3525 2825);
PAINT PURPLE (-3525 2825);
FORCENOTE
BMC
(-3525 2925) 0;
DISPLAY LEFT (-3525 2925);
DISPLAY 1.021277 (-3525 2925);
PAINT PURPLE (-3525 2925);
FORCENOTE
DEBUG FOR:
(-3625 3225) 0;
DISPLAY LEFT (-3625 3225);
DISPLAY 1.021277 (-3625 3225);
PAINT PURPLE (-3625 3225);
FORCENOTE
TP FAB3 ADD BMC REMOTE CIRCUIT 1003
(2025 4875) 0;
DISPLAY LEFT (2025 4875);
DISPLAY 1.021277 (2025 4875);
PAINT RED (2025 4875);
FORCENOTE
TP FAB4 CHANGE A SIDE CONNECTION 20170111
(2025 4800) 0;
DISPLAY LEFT (2025 4800);
DISPLAY 1.021277 (2025 4800);
PAINT RED (2025 4800);
FORCENOTE
$CDS_IMAGE|JTAG Block Diagram_20170103.jpg|2665|2000
(2775 1400) 0;
DISPLAY LEFT (2775 1400);
QUIT
